FILE_TYPE = MACRO_DRAWING;
SET COLOR_WIRE YELLOW;
SET COLOR_PROP ORANGE;
SET COLOR_DOT WHITE;
SET COLOR_ARC YELLOW;
SET COLOR_BODY GREEN;
SET COLOR_NOTE PURPLE;
SET PROP_DISPLAY VALUE;
SET PAGE_NUMBER P31;
FORCEADD GENOA_SP5..28
(-8600 3400);
FORCEPROP 1 LAST LOCATION U25
J 0
(-9000 6600);
DISPLAY 0.489362 (-9000 6600);
PAINT SKYBLUE (-9000 6600);
FORCEPROP 0 LAST $SEC 28
J 0
(-8975 6800);
DISPLAY 0.680851 (-8975 6800);
PAINT MONO (-8975 6800);
DISPLAY INVISIBLE (-8975 6800);
FORCEPROP 0 LAST CDS_SEC 28
J 0
(-9000 6700);
DISPLAY 1.021277 (-9000 6700);
DISPLAY INVISIBLE (-9000 6700);
FORCEPROP 0 LASTPIN (-9150 6350) $PN A3
J 2
(-9160 6360);
DISPLAY 0.489362 (-9160 6360);
PAINT MONO (-9160 6360);
FORCEPROP 0 LASTPIN (-9150 6300) $PN A9
J 2
(-9160 6310);
DISPLAY 0.489362 (-9160 6310);
PAINT MONO (-9160 6310);
FORCEPROP 0 LASTPIN (-9150 6250) $PN A15
J 2
(-9160 6260);
DISPLAY 0.489362 (-9160 6260);
PAINT MONO (-9160 6260);
FORCEPROP 0 LASTPIN (-9150 6200) $PN A21
J 2
(-9160 6210);
DISPLAY 0.489362 (-9160 6210);
PAINT MONO (-9160 6210);
FORCEPROP 0 LASTPIN (-9150 6150) $PN A27
J 2
(-9160 6160);
DISPLAY 0.489362 (-9160 6160);
PAINT MONO (-9160 6160);
FORCEPROP 0 LASTPIN (-9150 6100) $PN A43
J 2
(-9160 6110);
DISPLAY 0.489362 (-9160 6110);
PAINT MONO (-9160 6110);
FORCEPROP 0 LASTPIN (-9150 6050) $PN A44
J 2
(-9160 6060);
DISPLAY 0.489362 (-9160 6060);
PAINT MONO (-9160 6060);
FORCEPROP 0 LASTPIN (-9150 6000) $PN A47
J 2
(-9160 6010);
DISPLAY 0.489362 (-9160 6010);
PAINT MONO (-9160 6010);
FORCEPROP 0 LASTPIN (-9150 5950) $PN A49
J 2
(-9160 5960);
DISPLAY 0.489362 (-9160 5960);
PAINT MONO (-9160 5960);
FORCEPROP 0 LASTPIN (-9150 5900) $PN A53
J 2
(-9160 5910);
DISPLAY 0.489362 (-9160 5910);
PAINT MONO (-9160 5910);
FORCEPROP 0 LASTPIN (-9150 5850) $PN A61
J 2
(-9160 5860);
DISPLAY 0.489362 (-9160 5860);
PAINT MONO (-9160 5860);
FORCEPROP 0 LASTPIN (-9150 5800) $PN A67
J 2
(-9160 5810);
DISPLAY 0.489362 (-9160 5810);
PAINT MONO (-9160 5810);
FORCEPROP 0 LASTPIN (-9150 5750) $PN A72
J 2
(-9160 5760);
DISPLAY 0.489362 (-9160 5760);
PAINT MONO (-9160 5760);
FORCEPROP 0 LASTPIN (-9150 5700) $PN A73
J 2
(-9160 5710);
DISPLAY 0.489362 (-9160 5710);
PAINT MONO (-9160 5710);
FORCEPROP 0 LASTPIN (-9150 5650) $PN B7
J 2
(-9160 5660);
DISPLAY 0.489362 (-9160 5660);
PAINT MONO (-9160 5660);
FORCEPROP 0 LASTPIN (-9150 5600) $PN B8
J 2
(-9160 5610);
DISPLAY 0.489362 (-9160 5610);
PAINT MONO (-9160 5610);
FORCEPROP 0 LASTPIN (-9150 5550) $PN B10
J 2
(-9160 5560);
DISPLAY 0.489362 (-9160 5560);
PAINT MONO (-9160 5560);
FORCEPROP 0 LASTPIN (-9150 5500) $PN B11
J 2
(-9160 5510);
DISPLAY 0.489362 (-9160 5510);
PAINT MONO (-9160 5510);
FORCEPROP 0 LASTPIN (-9150 5450) $PN B13
J 2
(-9160 5460);
DISPLAY 0.489362 (-9160 5460);
PAINT MONO (-9160 5460);
FORCEPROP 0 LASTPIN (-9150 5400) $PN B18
J 2
(-9160 5410);
DISPLAY 0.489362 (-9160 5410);
PAINT MONO (-9160 5410);
FORCEPROP 0 LASTPIN (-9150 5350) $PN B24
J 2
(-9160 5360);
DISPLAY 0.489362 (-9160 5360);
PAINT MONO (-9160 5360);
FORCEPROP 0 LASTPIN (-9150 5300) $PN B27
J 2
(-9160 5310);
DISPLAY 0.489362 (-9160 5310);
PAINT MONO (-9160 5310);
FORCEPROP 0 LASTPIN (-9150 5250) $PN B30
J 2
(-9160 5260);
DISPLAY 0.489362 (-9160 5260);
PAINT MONO (-9160 5260);
FORCEPROP 0 LASTPIN (-9150 5200) $PN B33
J 2
(-9160 5210);
DISPLAY 0.489362 (-9160 5210);
PAINT MONO (-9160 5210);
FORCEPROP 0 LASTPIN (-9150 5150) $PN B37
J 2
(-9160 5160);
DISPLAY 0.489362 (-9160 5160);
PAINT MONO (-9160 5160);
FORCEPROP 0 LASTPIN (-9150 5100) $PN B39
J 2
(-9160 5110);
DISPLAY 0.489362 (-9160 5110);
PAINT MONO (-9160 5110);
FORCEPROP 0 LASTPIN (-9150 5050) $PN B43
J 2
(-9160 5060);
DISPLAY 0.489362 (-9160 5060);
PAINT MONO (-9160 5060);
FORCEPROP 0 LASTPIN (-9150 5000) $PN B46
J 2
(-9160 5010);
DISPLAY 0.489362 (-9160 5010);
PAINT MONO (-9160 5010);
FORCEPROP 0 LASTPIN (-9150 4950) $PN B49
J 2
(-9160 4960);
DISPLAY 0.489362 (-9160 4960);
PAINT MONO (-9160 4960);
FORCEPROP 0 LASTPIN (-9150 4900) $PN B52
J 2
(-9160 4910);
DISPLAY 0.489362 (-9160 4910);
PAINT MONO (-9160 4910);
FORCEPROP 0 LASTPIN (-9150 4850) $PN B55
J 2
(-9160 4860);
DISPLAY 0.489362 (-9160 4860);
PAINT MONO (-9160 4860);
FORCEPROP 0 LASTPIN (-9150 4800) $PN B59
J 2
(-9160 4810);
DISPLAY 0.489362 (-9160 4810);
PAINT MONO (-9160 4810);
FORCEPROP 0 LASTPIN (-9150 4750) $PN B62
J 2
(-9160 4760);
DISPLAY 0.489362 (-9160 4760);
PAINT MONO (-9160 4760);
FORCEPROP 0 LASTPIN (-9150 4700) $PN B65
J 2
(-9160 4710);
DISPLAY 0.489362 (-9160 4710);
PAINT MONO (-9160 4710);
FORCEPROP 0 LASTPIN (-9150 4650) $PN B68
J 2
(-9160 4660);
DISPLAY 0.489362 (-9160 4660);
PAINT MONO (-9160 4660);
FORCEPROP 0 LASTPIN (-9150 4600) $PN B70
J 2
(-9160 4610);
DISPLAY 0.489362 (-9160 4610);
PAINT MONO (-9160 4610);
FORCEPROP 0 LASTPIN (-9150 4550) $PN C1
J 2
(-9160 4560);
DISPLAY 0.489362 (-9160 4560);
PAINT MONO (-9160 4560);
FORCEPROP 0 LASTPIN (-9150 4500) $PN C5
J 2
(-9160 4510);
DISPLAY 0.489362 (-9160 4510);
PAINT MONO (-9160 4510);
FORCEPROP 0 LASTPIN (-9150 4450) $PN C8
J 2
(-9160 4460);
DISPLAY 0.489362 (-9160 4460);
PAINT MONO (-9160 4460);
FORCEPROP 0 LASTPIN (-9150 4400) $PN C10
J 2
(-9160 4410);
DISPLAY 0.489362 (-9160 4410);
PAINT MONO (-9160 4410);
FORCEPROP 0 LASTPIN (-9150 4350) $PN C11
J 2
(-9160 4360);
DISPLAY 0.489362 (-9160 4360);
PAINT MONO (-9160 4360);
FORCEPROP 0 LASTPIN (-9150 4300) $PN C13
J 2
(-9160 4310);
DISPLAY 0.489362 (-9160 4310);
PAINT MONO (-9160 4310);
FORCEPROP 0 LASTPIN (-9150 4250) $PN C15
J 2
(-9160 4260);
DISPLAY 0.489362 (-9160 4260);
PAINT MONO (-9160 4260);
FORCEPROP 0 LASTPIN (-9150 4200) $PN C21
J 2
(-9160 4210);
DISPLAY 0.489362 (-9160 4210);
PAINT MONO (-9160 4210);
FORCEPROP 0 LASTPIN (-9150 4150) $PN C24
J 2
(-9160 4160);
DISPLAY 0.489362 (-9160 4160);
PAINT MONO (-9160 4160);
FORCEPROP 0 LASTPIN (-9150 4100) $PN C27
J 2
(-9160 4110);
DISPLAY 0.489362 (-9160 4110);
PAINT MONO (-9160 4110);
FORCEPROP 0 LASTPIN (-9150 4050) $PN C30
J 2
(-9160 4060);
DISPLAY 0.489362 (-9160 4060);
PAINT MONO (-9160 4060);
FORCEPROP 0 LASTPIN (-9150 4000) $PN C36
J 2
(-9160 4010);
DISPLAY 0.489362 (-9160 4010);
PAINT MONO (-9160 4010);
FORCEPROP 0 LASTPIN (-9150 3950) $PN C40
J 2
(-9160 3960);
DISPLAY 0.489362 (-9160 3960);
PAINT MONO (-9160 3960);
FORCEPROP 0 LASTPIN (-9150 3900) $PN C43
J 2
(-9160 3910);
DISPLAY 0.489362 (-9160 3910);
PAINT MONO (-9160 3910);
FORCEPROP 0 LASTPIN (-9150 3850) $PN C46
J 2
(-9160 3860);
DISPLAY 0.489362 (-9160 3860);
PAINT MONO (-9160 3860);
FORCEPROP 0 LASTPIN (-9150 3800) $PN C49
J 2
(-9160 3810);
DISPLAY 0.489362 (-9160 3810);
PAINT MONO (-9160 3810);
FORCEPROP 0 LASTPIN (-9150 3750) $PN C52
J 2
(-9160 3760);
DISPLAY 0.489362 (-9160 3760);
PAINT MONO (-9160 3760);
FORCEPROP 0 LASTPIN (-9150 3700) $PN C55
J 2
(-9160 3710);
DISPLAY 0.489362 (-9160 3710);
PAINT MONO (-9160 3710);
FORCEPROP 0 LASTPIN (-9150 3650) $PN C56
J 2
(-9160 3660);
DISPLAY 0.489362 (-9160 3660);
PAINT MONO (-9160 3660);
FORCEPROP 0 LASTPIN (-9150 3600) $PN C57
J 2
(-9160 3610);
DISPLAY 0.489362 (-9160 3610);
PAINT MONO (-9160 3610);
FORCEPROP 0 LASTPIN (-9150 3550) $PN C61
J 2
(-9160 3560);
DISPLAY 0.489362 (-9160 3560);
PAINT MONO (-9160 3560);
FORCEPROP 0 LASTPIN (-9150 3500) $PN C64
J 2
(-9160 3510);
DISPLAY 0.489362 (-9160 3510);
PAINT MONO (-9160 3510);
FORCEPROP 0 LASTPIN (-9150 3450) $PN C67
J 2
(-9160 3460);
DISPLAY 0.489362 (-9160 3460);
PAINT MONO (-9160 3460);
FORCEPROP 0 LASTPIN (-9150 3400) $PN C69
J 2
(-9160 3410);
DISPLAY 0.489362 (-9160 3410);
PAINT MONO (-9160 3410);
FORCEPROP 0 LASTPIN (-9150 3350) $PN C71
J 2
(-9160 3360);
DISPLAY 0.489362 (-9160 3360);
PAINT MONO (-9160 3360);
FORCEPROP 0 LASTPIN (-9150 3300) $PN C73
J 2
(-9160 3310);
DISPLAY 0.489362 (-9160 3310);
PAINT MONO (-9160 3310);
FORCEPROP 0 LASTPIN (-9150 3250) $PN C75
J 2
(-9160 3260);
DISPLAY 0.489362 (-9160 3260);
PAINT MONO (-9160 3260);
FORCEPROP 0 LASTPIN (-9150 3200) $PN D2
J 2
(-9160 3210);
DISPLAY 0.489362 (-9160 3210);
PAINT MONO (-9160 3210);
FORCEPROP 0 LASTPIN (-9150 3150) $PN D3
J 2
(-9160 3160);
DISPLAY 0.489362 (-9160 3160);
PAINT MONO (-9160 3160);
FORCEPROP 0 LASTPIN (-9150 3100) $PN D5
J 2
(-9160 3110);
DISPLAY 0.489362 (-9160 3110);
PAINT MONO (-9160 3110);
FORCEPROP 0 LASTPIN (-9150 3050) $PN D6
J 2
(-9160 3060);
DISPLAY 0.489362 (-9160 3060);
PAINT MONO (-9160 3060);
FORCEPROP 0 LASTPIN (-9150 3000) $PN D9
J 2
(-9160 3010);
DISPLAY 0.489362 (-9160 3010);
PAINT MONO (-9160 3010);
FORCEPROP 0 LASTPIN (-9150 2950) $PN D10
J 2
(-9160 2960);
DISPLAY 0.489362 (-9160 2960);
PAINT MONO (-9160 2960);
FORCEPROP 0 LASTPIN (-9150 2900) $PN D12
J 2
(-9160 2910);
DISPLAY 0.489362 (-9160 2910);
PAINT MONO (-9160 2910);
FORCEPROP 0 LASTPIN (-9150 2850) $PN D13
J 2
(-9160 2860);
DISPLAY 0.489362 (-9160 2860);
PAINT MONO (-9160 2860);
FORCEPROP 0 LASTPIN (-9150 2800) $PN D16
J 2
(-9160 2810);
DISPLAY 0.489362 (-9160 2810);
PAINT MONO (-9160 2810);
FORCEPROP 0 LASTPIN (-9150 2750) $PN D17
J 2
(-9160 2760);
DISPLAY 0.489362 (-9160 2760);
PAINT MONO (-9160 2760);
FORCEPROP 0 LASTPIN (-9150 2700) $PN D19
J 2
(-9160 2710);
DISPLAY 0.489362 (-9160 2710);
PAINT MONO (-9160 2710);
FORCEPROP 0 LASTPIN (-9150 2650) $PN D20
J 2
(-9160 2660);
DISPLAY 0.489362 (-9160 2660);
PAINT MONO (-9160 2660);
FORCEPROP 0 LASTPIN (-9150 2600) $PN D21
J 2
(-9160 2610);
DISPLAY 0.489362 (-9160 2610);
PAINT MONO (-9160 2610);
FORCEPROP 0 LASTPIN (-9150 2550) $PN D24
J 2
(-9160 2560);
DISPLAY 0.489362 (-9160 2560);
PAINT MONO (-9160 2560);
FORCEPROP 0 LASTPIN (-9150 2500) $PN D25
J 2
(-9160 2510);
DISPLAY 0.489362 (-9160 2510);
PAINT MONO (-9160 2510);
FORCEPROP 0 LASTPIN (-9150 2450) $PN D26
J 2
(-9160 2460);
DISPLAY 0.489362 (-9160 2460);
PAINT MONO (-9160 2460);
FORCEPROP 0 LASTPIN (-9150 2400) $PN D27
J 2
(-9160 2410);
DISPLAY 0.489362 (-9160 2410);
PAINT MONO (-9160 2410);
FORCEPROP 0 LASTPIN (-9150 2350) $PN D28
J 2
(-9160 2360);
DISPLAY 0.489362 (-9160 2360);
PAINT MONO (-9160 2360);
FORCEPROP 0 LASTPIN (-9150 2300) $PN D29
J 2
(-9160 2310);
DISPLAY 0.489362 (-9160 2310);
PAINT MONO (-9160 2310);
FORCEPROP 0 LASTPIN (-9150 2250) $PN D30
J 2
(-9160 2260);
DISPLAY 0.489362 (-9160 2260);
PAINT MONO (-9160 2260);
FORCEPROP 0 LASTPIN (-9150 2200) $PN D31
J 2
(-9160 2210);
DISPLAY 0.489362 (-9160 2210);
PAINT MONO (-9160 2210);
FORCEPROP 0 LASTPIN (-9150 2150) $PN D35
J 2
(-9160 2160);
DISPLAY 0.489362 (-9160 2160);
PAINT MONO (-9160 2160);
FORCEPROP 0 LASTPIN (-9150 2100) $PN D37
J 2
(-9160 2110);
DISPLAY 0.489362 (-9160 2110);
PAINT MONO (-9160 2110);
FORCEPROP 0 LASTPIN (-9150 2050) $PN D39
J 2
(-9160 2060);
DISPLAY 0.489362 (-9160 2060);
PAINT MONO (-9160 2060);
FORCEPROP 0 LASTPIN (-9150 2000) $PN D40
J 2
(-9160 2010);
DISPLAY 0.489362 (-9160 2010);
PAINT MONO (-9160 2010);
FORCEPROP 0 LASTPIN (-9150 1950) $PN D41
J 2
(-9160 1960);
DISPLAY 0.489362 (-9160 1960);
PAINT MONO (-9160 1960);
FORCEPROP 0 LASTPIN (-9150 1900) $PN D42
J 2
(-9160 1910);
DISPLAY 0.489362 (-9160 1910);
PAINT MONO (-9160 1910);
FORCEPROP 0 LASTPIN (-9150 1850) $PN D43
J 2
(-9160 1860);
DISPLAY 0.489362 (-9160 1860);
PAINT MONO (-9160 1860);
FORCEPROP 0 LASTPIN (-9150 1800) $PN D44
J 2
(-9160 1810);
DISPLAY 0.489362 (-9160 1810);
PAINT MONO (-9160 1810);
FORCEPROP 0 LASTPIN (-9150 1750) $PN D45
J 2
(-9160 1760);
DISPLAY 0.489362 (-9160 1760);
PAINT MONO (-9160 1760);
FORCEPROP 0 LASTPIN (-9150 1700) $PN D46
J 2
(-9160 1710);
DISPLAY 0.489362 (-9160 1710);
PAINT MONO (-9160 1710);
FORCEPROP 0 LASTPIN (-9150 1650) $PN D47
J 2
(-9160 1660);
DISPLAY 0.489362 (-9160 1660);
PAINT MONO (-9160 1660);
FORCEPROP 0 LASTPIN (-9150 1600) $PN D48
J 2
(-9160 1610);
DISPLAY 0.489362 (-9160 1610);
PAINT MONO (-9160 1610);
FORCEPROP 0 LASTPIN (-9150 1550) $PN D49
J 2
(-9160 1560);
DISPLAY 0.489362 (-9160 1560);
PAINT MONO (-9160 1560);
FORCEPROP 0 LASTPIN (-9150 1500) $PN D50
J 2
(-9160 1510);
DISPLAY 0.489362 (-9160 1510);
PAINT MONO (-9160 1510);
FORCEPROP 0 LASTPIN (-9150 1450) $PN D51
J 2
(-9160 1460);
DISPLAY 0.489362 (-9160 1460);
PAINT MONO (-9160 1460);
FORCEPROP 0 LASTPIN (-9150 1400) $PN D52
J 2
(-9160 1410);
DISPLAY 0.489362 (-9160 1410);
PAINT MONO (-9160 1410);
FORCEPROP 0 LASTPIN (-9150 1350) $PN D53
J 2
(-9160 1360);
DISPLAY 0.489362 (-9160 1360);
PAINT MONO (-9160 1360);
FORCEPROP 0 LASTPIN (-9150 1300) $PN D54
J 2
(-9160 1310);
DISPLAY 0.489362 (-9160 1310);
PAINT MONO (-9160 1310);
FORCEPROP 0 LASTPIN (-9150 1250) $PN D57
J 2
(-9160 1260);
DISPLAY 0.489362 (-9160 1260);
PAINT MONO (-9160 1260);
FORCEPROP 0 LASTPIN (-9150 1200) $PN D59
J 2
(-9160 1210);
DISPLAY 0.489362 (-9160 1210);
PAINT MONO (-9160 1210);
FORCEPROP 0 LASTPIN (-9150 1150) $PN D60
J 2
(-9160 1160);
DISPLAY 0.489362 (-9160 1160);
PAINT MONO (-9160 1160);
FORCEPROP 0 LASTPIN (-9150 1100) $PN D61
J 2
(-9160 1110);
DISPLAY 0.489362 (-9160 1110);
PAINT MONO (-9160 1110);
FORCEPROP 0 LASTPIN (-9150 1050) $PN D63
J 2
(-9160 1060);
DISPLAY 0.489362 (-9160 1060);
PAINT MONO (-9160 1060);
FORCEPROP 0 LASTPIN (-9150 1000) $PN D64
J 2
(-9160 1010);
DISPLAY 0.489362 (-9160 1010);
PAINT MONO (-9160 1010);
FORCEPROP 0 LASTPIN (-9150 950) $PN D66
J 2
(-9160 960);
DISPLAY 0.489362 (-9160 960);
PAINT MONO (-9160 960);
FORCEPROP 0 LASTPIN (-9150 900) $PN D67
J 2
(-9160 910);
DISPLAY 0.489362 (-9160 910);
PAINT MONO (-9160 910);
FORCEPROP 0 LASTPIN (-9150 850) $PN D70
J 2
(-9160 860);
DISPLAY 0.489362 (-9160 860);
PAINT MONO (-9160 860);
FORCEPROP 0 LASTPIN (-9150 800) $PN D71
J 2
(-9160 810);
DISPLAY 0.489362 (-9160 810);
PAINT MONO (-9160 810);
FORCEPROP 0 LASTPIN (-9150 750) $PN D73
J 2
(-9160 760);
DISPLAY 0.489362 (-9160 760);
PAINT MONO (-9160 760);
FORCEPROP 0 LASTPIN (-9150 700) $PN D74
J 2
(-9160 710);
DISPLAY 0.489362 (-9160 710);
PAINT MONO (-9160 710);
FORCEPROP 0 LASTPIN (-9150 650) $PN E1
J 2
(-9160 660);
DISPLAY 0.489362 (-9160 660);
PAINT MONO (-9160 660);
FORCEPROP 0 LASTPIN (-9150 600) $PN E3
J 2
(-9160 610);
DISPLAY 0.489362 (-9160 610);
PAINT MONO (-9160 610);
FORCEPROP 0 LASTPIN (-9150 550) $PN E6
J 2
(-9160 560);
DISPLAY 0.489362 (-9160 560);
PAINT MONO (-9160 560);
FORCEPROP 0 LASTPIN (-9150 500) $PN E7
J 2
(-9160 510);
DISPLAY 0.489362 (-9160 510);
PAINT MONO (-9160 510);
FORCEPROP 0 LASTPIN (-9150 450) $PN E8
J 2
(-9160 460);
DISPLAY 0.489362 (-9160 460);
PAINT MONO (-9160 460);
FORCEPROP 0 LASTPIN (-8050 6350) $PN E10
J 0
(-8040 6360);
DISPLAY 0.489362 (-8040 6360);
PAINT MONO (-8040 6360);
FORCEPROP 0 LASTPIN (-8050 6300) $PN E13
J 0
(-8040 6310);
DISPLAY 0.489362 (-8040 6310);
PAINT MONO (-8040 6310);
FORCEPROP 0 LASTPIN (-8050 6250) $PN E14
J 0
(-8040 6260);
DISPLAY 0.489362 (-8040 6260);
PAINT MONO (-8040 6260);
FORCEPROP 0 LASTPIN (-8050 6200) $PN E15
J 0
(-8040 6210);
DISPLAY 0.489362 (-8040 6210);
PAINT MONO (-8040 6210);
FORCEPROP 0 LASTPIN (-8050 6150) $PN E17
J 0
(-8040 6160);
DISPLAY 0.489362 (-8040 6160);
PAINT MONO (-8040 6160);
FORCEPROP 0 LASTPIN (-8050 6100) $PN E18
J 0
(-8040 6110);
DISPLAY 0.489362 (-8040 6110);
PAINT MONO (-8040 6110);
FORCEPROP 0 LASTPIN (-8050 6050) $PN E20
J 0
(-8040 6060);
DISPLAY 0.489362 (-8040 6060);
PAINT MONO (-8040 6060);
FORCEPROP 0 LASTPIN (-8050 6000) $PN E21
J 0
(-8040 6010);
DISPLAY 0.489362 (-8040 6010);
PAINT MONO (-8040 6010);
FORCEPROP 0 LASTPIN (-8050 5950) $PN E52
J 0
(-8040 5960);
DISPLAY 0.489362 (-8040 5960);
PAINT MONO (-8040 5960);
FORCEPROP 0 LASTPIN (-8050 5900) $PN E53
J 0
(-8040 5910);
DISPLAY 0.489362 (-8040 5910);
PAINT MONO (-8040 5910);
FORCEPROP 0 LASTPIN (-8050 5850) $PN E55
J 0
(-8040 5860);
DISPLAY 0.489362 (-8040 5860);
PAINT MONO (-8040 5860);
FORCEPROP 0 LASTPIN (-8050 5800) $PN E56
J 0
(-8040 5810);
DISPLAY 0.489362 (-8040 5810);
PAINT MONO (-8040 5810);
FORCEPROP 0 LASTPIN (-8050 5750) $PN E58
J 0
(-8040 5760);
DISPLAY 0.489362 (-8040 5760);
PAINT MONO (-8040 5760);
FORCEPROP 0 LASTPIN (-8050 5700) $PN E59
J 0
(-8040 5710);
DISPLAY 0.489362 (-8040 5710);
PAINT MONO (-8040 5710);
FORCEPROP 0 LASTPIN (-8050 5650) $PN E61
J 0
(-8040 5660);
DISPLAY 0.489362 (-8040 5660);
PAINT MONO (-8040 5660);
FORCEPROP 0 LASTPIN (-8050 5600) $PN E62
J 0
(-8040 5610);
DISPLAY 0.489362 (-8040 5610);
PAINT MONO (-8040 5610);
FORCEPROP 0 LASTPIN (-8050 5550) $PN E63
J 0
(-8040 5560);
DISPLAY 0.489362 (-8040 5560);
PAINT MONO (-8040 5560);
FORCEPROP 0 LASTPIN (-8050 5500) $PN E65
J 0
(-8040 5510);
DISPLAY 0.489362 (-8040 5510);
PAINT MONO (-8040 5510);
FORCEPROP 0 LASTPIN (-8050 5450) $PN E66
J 0
(-8040 5460);
DISPLAY 0.489362 (-8040 5460);
PAINT MONO (-8040 5460);
FORCEPROP 0 LASTPIN (-8050 5400) $PN E68
J 0
(-8040 5410);
DISPLAY 0.489362 (-8040 5410);
PAINT MONO (-8040 5410);
FORCEPROP 0 LASTPIN (-8050 5350) $PN E69
J 0
(-8040 5360);
DISPLAY 0.489362 (-8040 5360);
PAINT MONO (-8040 5360);
FORCEPROP 0 LASTPIN (-8050 5300) $PN E70
J 0
(-8040 5310);
DISPLAY 0.489362 (-8040 5310);
PAINT MONO (-8040 5310);
FORCEPROP 0 LASTPIN (-8050 5250) $PN E72
J 0
(-8040 5260);
DISPLAY 0.489362 (-8040 5260);
PAINT MONO (-8040 5260);
FORCEPROP 0 LASTPIN (-8050 5200) $PN E73
J 0
(-8040 5210);
DISPLAY 0.489362 (-8040 5210);
PAINT MONO (-8040 5210);
FORCEPROP 0 LASTPIN (-8050 5150) $PN E75
J 0
(-8040 5160);
DISPLAY 0.489362 (-8040 5160);
PAINT MONO (-8040 5160);
FORCEPROP 0 LASTPIN (-8050 5100) $PN F3
J 0
(-8040 5110);
DISPLAY 0.489362 (-8040 5110);
PAINT MONO (-8040 5110);
FORCEPROP 0 LASTPIN (-8050 5050) $PN F5
J 0
(-8040 5060);
DISPLAY 0.489362 (-8040 5060);
PAINT MONO (-8040 5060);
FORCEPROP 0 LASTPIN (-8050 5000) $PN F8
J 0
(-8040 5010);
DISPLAY 0.489362 (-8040 5010);
PAINT MONO (-8040 5010);
FORCEPROP 0 LASTPIN (-8050 4950) $PN F10
J 0
(-8040 4960);
DISPLAY 0.489362 (-8040 4960);
PAINT MONO (-8040 4960);
FORCEPROP 0 LASTPIN (-8050 4900) $PN F12
J 0
(-8040 4910);
DISPLAY 0.489362 (-8040 4910);
PAINT MONO (-8040 4910);
FORCEPROP 0 LASTPIN (-8050 4850) $PN F15
J 0
(-8040 4860);
DISPLAY 0.489362 (-8040 4860);
PAINT MONO (-8040 4860);
FORCEPROP 0 LASTPIN (-8050 4800) $PN F17
J 0
(-8040 4810);
DISPLAY 0.489362 (-8040 4810);
PAINT MONO (-8040 4810);
FORCEPROP 0 LASTPIN (-8050 4750) $PN F19
J 0
(-8040 4760);
DISPLAY 0.489362 (-8040 4760);
PAINT MONO (-8040 4760);
FORCEPROP 0 LASTPIN (-8050 4700) $PN F23
J 0
(-8040 4710);
DISPLAY 0.489362 (-8040 4710);
PAINT MONO (-8040 4710);
FORCEPROP 0 LASTPIN (-8050 4650) $PN F24
J 0
(-8040 4660);
DISPLAY 0.489362 (-8040 4660);
PAINT MONO (-8040 4660);
FORCEPROP 0 LASTPIN (-8050 4600) $PN F26
J 0
(-8040 4610);
DISPLAY 0.489362 (-8040 4610);
PAINT MONO (-8040 4610);
FORCEPROP 0 LASTPIN (-8050 4550) $PN F27
J 0
(-8040 4560);
DISPLAY 0.489362 (-8040 4560);
PAINT MONO (-8040 4560);
FORCEPROP 0 LASTPIN (-8050 4500) $PN F29
J 0
(-8040 4510);
DISPLAY 0.489362 (-8040 4510);
PAINT MONO (-8040 4510);
FORCEPROP 0 LASTPIN (-8050 4450) $PN F30
J 0
(-8040 4460);
DISPLAY 0.489362 (-8040 4460);
PAINT MONO (-8040 4460);
FORCEPROP 0 LASTPIN (-8050 4400) $PN F32
J 0
(-8040 4410);
DISPLAY 0.489362 (-8040 4410);
PAINT MONO (-8040 4410);
FORCEPROP 0 LASTPIN (-8050 4350) $PN F33
J 0
(-8040 4360);
DISPLAY 0.489362 (-8040 4360);
PAINT MONO (-8040 4360);
FORCEPROP 0 LASTPIN (-8050 4300) $PN F35
J 0
(-8040 4310);
DISPLAY 0.489362 (-8040 4310);
PAINT MONO (-8040 4310);
FORCEPROP 0 LASTPIN (-8050 4250) $PN F36
J 0
(-8040 4260);
DISPLAY 0.489362 (-8040 4260);
PAINT MONO (-8040 4260);
FORCEPROP 0 LASTPIN (-8050 4200) $PN F37
J 0
(-8040 4210);
DISPLAY 0.489362 (-8040 4210);
PAINT MONO (-8040 4210);
FORCEPROP 0 LASTPIN (-8050 4150) $PN F39
J 0
(-8040 4160);
DISPLAY 0.489362 (-8040 4160);
PAINT MONO (-8040 4160);
FORCEPROP 0 LASTPIN (-8050 4100) $PN F40
J 0
(-8040 4110);
DISPLAY 0.489362 (-8040 4110);
PAINT MONO (-8040 4110);
FORCEPROP 0 LASTPIN (-8050 4050) $PN F41
J 0
(-8040 4060);
DISPLAY 0.489362 (-8040 4060);
PAINT MONO (-8040 4060);
FORCEPROP 0 LASTPIN (-8050 4000) $PN F43
J 0
(-8040 4010);
DISPLAY 0.489362 (-8040 4010);
PAINT MONO (-8040 4010);
FORCEPROP 0 LASTPIN (-8050 3950) $PN F44
J 0
(-8040 3960);
DISPLAY 0.489362 (-8040 3960);
PAINT MONO (-8040 3960);
FORCEPROP 0 LASTPIN (-8050 3900) $PN F46
J 0
(-8040 3910);
DISPLAY 0.489362 (-8040 3910);
PAINT MONO (-8040 3910);
FORCEPROP 0 LASTPIN (-8050 3850) $PN F47
J 0
(-8040 3860);
DISPLAY 0.489362 (-8040 3860);
PAINT MONO (-8040 3860);
FORCEPROP 0 LASTPIN (-8050 3800) $PN F49
J 0
(-8040 3810);
DISPLAY 0.489362 (-8040 3810);
PAINT MONO (-8040 3810);
FORCEPROP 0 LASTPIN (-8050 3750) $PN F50
J 0
(-8040 3760);
DISPLAY 0.489362 (-8040 3760);
PAINT MONO (-8040 3760);
FORCEPROP 0 LASTPIN (-8050 3700) $PN F52
J 0
(-8040 3710);
DISPLAY 0.489362 (-8040 3710);
PAINT MONO (-8040 3710);
FORCEPROP 0 LASTPIN (-8050 3650) $PN F53
J 0
(-8040 3660);
DISPLAY 0.489362 (-8040 3660);
PAINT MONO (-8040 3660);
FORCEPROP 0 LASTPIN (-8050 3600) $PN F57
J 0
(-8040 3610);
DISPLAY 0.489362 (-8040 3610);
PAINT MONO (-8040 3610);
FORCEPROP 0 LASTPIN (-8050 3550) $PN F59
J 0
(-8040 3560);
DISPLAY 0.489362 (-8040 3560);
PAINT MONO (-8040 3560);
FORCEPROP 0 LASTPIN (-8050 3500) $PN F61
J 0
(-8040 3510);
DISPLAY 0.489362 (-8040 3510);
PAINT MONO (-8040 3510);
FORCEPROP 0 LASTPIN (-8050 3450) $PN F64
J 0
(-8040 3460);
DISPLAY 0.489362 (-8040 3460);
PAINT MONO (-8040 3460);
FORCEPROP 0 LASTPIN (-8050 3400) $PN F66
J 0
(-8040 3410);
DISPLAY 0.489362 (-8040 3410);
PAINT MONO (-8040 3410);
FORCEPROP 0 LASTPIN (-8050 3350) $PN F68
J 0
(-8040 3360);
DISPLAY 0.489362 (-8040 3360);
PAINT MONO (-8040 3360);
FORCEPROP 0 LASTPIN (-8050 3300) $PN F71
J 0
(-8040 3310);
DISPLAY 0.489362 (-8040 3310);
PAINT MONO (-8040 3310);
FORCEPROP 0 LASTPIN (-8050 3250) $PN F73
J 0
(-8040 3260);
DISPLAY 0.489362 (-8040 3260);
PAINT MONO (-8040 3260);
FORCEPROP 0 LASTPIN (-8050 3200) $PN G1
J 0
(-8040 3210);
DISPLAY 0.489362 (-8040 3210);
PAINT MONO (-8040 3210);
FORCEPROP 0 LASTPIN (-8050 3150) $PN G4
J 0
(-8040 3160);
DISPLAY 0.489362 (-8040 3160);
PAINT MONO (-8040 3160);
FORCEPROP 0 LASTPIN (-8050 3100) $PN G6
J 0
(-8040 3110);
DISPLAY 0.489362 (-8040 3110);
PAINT MONO (-8040 3110);
FORCEPROP 0 LASTPIN (-8050 3050) $PN G8
J 0
(-8040 3060);
DISPLAY 0.489362 (-8040 3060);
PAINT MONO (-8040 3060);
FORCEPROP 0 LASTPIN (-8050 3000) $PN G11
J 0
(-8040 3010);
DISPLAY 0.489362 (-8040 3010);
PAINT MONO (-8040 3010);
FORCEPROP 0 LASTPIN (-8050 2950) $PN G13
J 0
(-8040 2960);
DISPLAY 0.489362 (-8040 2960);
PAINT MONO (-8040 2960);
FORCEPROP 0 LASTPIN (-8050 2900) $PN G15
J 0
(-8040 2910);
DISPLAY 0.489362 (-8040 2910);
PAINT MONO (-8040 2910);
FORCEPROP 0 LASTPIN (-8050 2850) $PN G18
J 0
(-8040 2860);
DISPLAY 0.489362 (-8040 2860);
PAINT MONO (-8040 2860);
FORCEPROP 0 LASTPIN (-8050 2800) $PN G20
J 0
(-8040 2810);
DISPLAY 0.489362 (-8040 2810);
PAINT MONO (-8040 2810);
FORCEPROP 0 LASTPIN (-8050 2750) $PN G22
J 0
(-8040 2760);
DISPLAY 0.489362 (-8040 2760);
PAINT MONO (-8040 2760);
FORCEPROP 0 LASTPIN (-8050 2700) $PN G25
J 0
(-8040 2710);
DISPLAY 0.489362 (-8040 2710);
PAINT MONO (-8040 2710);
FORCEPROP 0 LASTPIN (-8050 2650) $PN G28
J 0
(-8040 2660);
DISPLAY 0.489362 (-8040 2660);
PAINT MONO (-8040 2660);
FORCEPROP 0 LASTPIN (-8050 2600) $PN G31
J 0
(-8040 2610);
DISPLAY 0.489362 (-8040 2610);
PAINT MONO (-8040 2610);
FORCEPROP 0 LASTPIN (-8050 2550) $PN G34
J 0
(-8040 2560);
DISPLAY 0.489362 (-8040 2560);
PAINT MONO (-8040 2560);
FORCEPROP 0 LASTPIN (-8050 2500) $PN G42
J 0
(-8040 2510);
DISPLAY 0.489362 (-8040 2510);
PAINT MONO (-8040 2510);
FORCEPROP 0 LASTPIN (-8050 2450) $PN G45
J 0
(-8040 2460);
DISPLAY 0.489362 (-8040 2460);
PAINT MONO (-8040 2460);
FORCEPROP 0 LASTPIN (-8050 2400) $PN G48
J 0
(-8040 2410);
DISPLAY 0.489362 (-8040 2410);
PAINT MONO (-8040 2410);
FORCEPROP 0 LASTPIN (-8050 2350) $PN G51
J 0
(-8040 2360);
DISPLAY 0.489362 (-8040 2360);
PAINT MONO (-8040 2360);
FORCEPROP 0 LASTPIN (-8050 2300) $PN G54
J 0
(-8040 2310);
DISPLAY 0.489362 (-8040 2310);
PAINT MONO (-8040 2310);
FORCEPROP 0 LASTPIN (-8050 2250) $PN G56
J 0
(-8040 2260);
DISPLAY 0.489362 (-8040 2260);
PAINT MONO (-8040 2260);
FORCEPROP 0 LASTPIN (-8050 2200) $PN G58
J 0
(-8040 2210);
DISPLAY 0.489362 (-8040 2210);
PAINT MONO (-8040 2210);
FORCEPROP 0 LASTPIN (-8050 2150) $PN G61
J 0
(-8040 2160);
DISPLAY 0.489362 (-8040 2160);
PAINT MONO (-8040 2160);
FORCEPROP 0 LASTPIN (-8050 2100) $PN G63
J 0
(-8040 2110);
DISPLAY 0.489362 (-8040 2110);
PAINT MONO (-8040 2110);
FORCEPROP 0 LASTPIN (-8050 2050) $PN G65
J 0
(-8040 2060);
DISPLAY 0.489362 (-8040 2060);
PAINT MONO (-8040 2060);
FORCEPROP 0 LASTPIN (-8050 2000) $PN G68
J 0
(-8040 2010);
DISPLAY 0.489362 (-8040 2010);
PAINT MONO (-8040 2010);
FORCEPROP 0 LASTPIN (-8050 1950) $PN G70
J 0
(-8040 1960);
DISPLAY 0.489362 (-8040 1960);
PAINT MONO (-8040 1960);
FORCEPROP 0 LASTPIN (-8050 1900) $PN G72
J 0
(-8040 1910);
DISPLAY 0.489362 (-8040 1910);
PAINT MONO (-8040 1910);
FORCEPROP 0 LASTPIN (-8050 1850) $PN G75
J 0
(-8040 1860);
DISPLAY 0.489362 (-8040 1860);
PAINT MONO (-8040 1860);
FORCEPROP 0 LASTPIN (-8050 1800) $PN H3
J 0
(-8040 1810);
DISPLAY 0.489362 (-8040 1810);
PAINT MONO (-8040 1810);
FORCEPROP 0 LASTPIN (-8050 1750) $PN H8
J 0
(-8040 1760);
DISPLAY 0.489362 (-8040 1760);
PAINT MONO (-8040 1760);
FORCEPROP 0 LASTPIN (-8050 1700) $PN H10
J 0
(-8040 1710);
DISPLAY 0.489362 (-8040 1710);
PAINT MONO (-8040 1710);
FORCEPROP 0 LASTPIN (-8050 1650) $PN H15
J 0
(-8040 1660);
DISPLAY 0.489362 (-8040 1660);
PAINT MONO (-8040 1660);
FORCEPROP 0 LASTPIN (-8050 1600) $PN H17
J 0
(-8040 1610);
DISPLAY 0.489362 (-8040 1610);
PAINT MONO (-8040 1610);
FORCEPROP 0 LASTPIN (-8050 1550) $PN H22
J 0
(-8040 1560);
DISPLAY 0.489362 (-8040 1560);
PAINT MONO (-8040 1560);
FORCEPROP 0 LASTPIN (-8050 1500) $PN H25
J 0
(-8040 1510);
DISPLAY 0.489362 (-8040 1510);
PAINT MONO (-8040 1510);
FORCEPROP 0 LASTPIN (-8050 1450) $PN H28
J 0
(-8040 1460);
DISPLAY 0.489362 (-8040 1460);
PAINT MONO (-8040 1460);
FORCEPROP 0 LASTPIN (-8050 1400) $PN H31
J 0
(-8040 1410);
DISPLAY 0.489362 (-8040 1410);
PAINT MONO (-8040 1410);
FORCEPROP 0 LASTPIN (-8050 1350) $PN H34
J 0
(-8040 1360);
DISPLAY 0.489362 (-8040 1360);
PAINT MONO (-8040 1360);
FORCEPROP 0 LASTPIN (-8050 1300) $PN H37
J 0
(-8040 1310);
DISPLAY 0.489362 (-8040 1310);
PAINT MONO (-8040 1310);
FORCEPROP 0 LASTPIN (-8050 1250) $PN H39
J 0
(-8040 1260);
DISPLAY 0.489362 (-8040 1260);
PAINT MONO (-8040 1260);
FORCEPROP 0 LASTPIN (-8050 1200) $PN H42
J 0
(-8040 1210);
DISPLAY 0.489362 (-8040 1210);
PAINT MONO (-8040 1210);
FORCEPROP 0 LASTPIN (-8050 1150) $PN H45
J 0
(-8040 1160);
DISPLAY 0.489362 (-8040 1160);
PAINT MONO (-8040 1160);
FORCEPROP 0 LASTPIN (-8050 1100) $PN H48
J 0
(-8040 1110);
DISPLAY 0.489362 (-8040 1110);
PAINT MONO (-8040 1110);
FORCEPROP 0 LASTPIN (-8050 1050) $PN H51
J 0
(-8040 1060);
DISPLAY 0.489362 (-8040 1060);
PAINT MONO (-8040 1060);
FORCEPROP 0 LASTPIN (-8050 1000) $PN H54
J 0
(-8040 1010);
DISPLAY 0.489362 (-8040 1010);
PAINT MONO (-8040 1010);
FORCEPROP 0 LASTPIN (-8050 950) $PN H59
J 0
(-8040 960);
DISPLAY 0.489362 (-8040 960);
PAINT MONO (-8040 960);
FORCEPROP 0 LASTPIN (-8050 900) $PN H61
J 0
(-8040 910);
DISPLAY 0.489362 (-8040 910);
PAINT MONO (-8040 910);
FORCEPROP 0 LASTPIN (-8050 850) $PN H66
J 0
(-8040 860);
DISPLAY 0.489362 (-8040 860);
PAINT MONO (-8040 860);
FORCEPROP 0 LASTPIN (-8050 800) $PN H68
J 0
(-8040 810);
DISPLAY 0.489362 (-8040 810);
PAINT MONO (-8040 810);
FORCEPROP 0 LASTPIN (-8050 750) $PN H73
J 0
(-8040 760);
DISPLAY 0.489362 (-8040 760);
PAINT MONO (-8040 760);
FORCEPROP 0 LASTPIN (-8050 700) $PN J1
J 0
(-8040 710);
DISPLAY 0.489362 (-8040 710);
PAINT MONO (-8040 710);
FORCEPROP 0 LASTPIN (-8050 650) $PN J4
J 0
(-8040 660);
DISPLAY 0.489362 (-8040 660);
PAINT MONO (-8040 660);
FORCEPROP 0 LASTPIN (-8050 600) $PN J6
J 0
(-8040 610);
DISPLAY 0.489362 (-8040 610);
PAINT MONO (-8040 610);
FORCEPROP 0 LASTPIN (-8050 550) $PN J8
J 0
(-8040 560);
DISPLAY 0.489362 (-8040 560);
PAINT MONO (-8040 560);
FORCEPROP 0 LASTPIN (-8050 500) $PN J11
J 0
(-8040 510);
DISPLAY 0.489362 (-8040 510);
PAINT MONO (-8040 510);
FORCEPROP 0 LASTPIN (-8050 450) $PN J13
J 0
(-8040 460);
DISPLAY 0.489362 (-8040 460);
PAINT MONO (-8040 460);
FORCEPROP 2 LAST PART_TYPE SMLF
J 0
(-9000 6700);
DISPLAY 1.021277 (-9000 6700);
FORCEPROP 1 LAST MATERIAL IO
J 0
(-8995 6482);
DISPLAY 0.489362 (-8995 6482);
PAINT SKYBLUE (-8995 6482);
FORCEPROP 2 LAST VALUE SOCKET6096_13568-001
J 0
(-9000 6550);
DISPLAY 0.489362 (-9000 6550);
PAINT SKYBLUE (-9000 6550);
FORCEPROP 2 LAST CDS_LIB pure_quanta
J 0
(-8600 3400);
DISPLAY INVISIBLE (-8600 3400);
FORCEPROP 1 LAST CDS_LMAN_SYM_OUTLINE -400,3050,400,-3050
J 0
(-8600 3400);
DISPLAY 0.468085 (-8600 3400);
PAINT GREEN (-8600 3400);
DISPLAY INVISIBLE (-8600 3400);
FORCEPROP 1 LAST NEEDS_NO_SIZE TRUE
J 0
(-8600 3400);
DISPLAY 0.723404 (-8600 3400);
PAINT GREEN (-8600 3400);
DISPLAY INVISIBLE (-8600 3400);
FORCEPROP 1 LAST PATH I19
J 0
(-8600 3400);
DISPLAY 0.723404 (-8600 3400);
PAINT GREEN (-8600 3400);
DISPLAY INVISIBLE (-8600 3400);
FORCEPROP 1 LAST PART_NUMBER DGA^6000030
J 0
(-9000 6650);
DISPLAY 0.489362 (-9000 6650);
PAINT SKYBLUE (-9000 6650);
DISPLAY INVISIBLE (-9000 6650);
FORCEADD GENOA_SP5..29
(-7075 3425);
FORCEPROP 1 LAST LOCATION U25
J 0
(-7470 6600);
DISPLAY 0.489362 (-7470 6600);
PAINT SKYBLUE (-7470 6600);
FORCEPROP 0 LAST $SEC 29
J 0
(-7450 6825);
DISPLAY 0.680851 (-7450 6825);
PAINT MONO (-7450 6825);
DISPLAY INVISIBLE (-7450 6825);
FORCEPROP 0 LAST CDS_SEC 29
J 0
(-7475 6725);
DISPLAY 1.021277 (-7475 6725);
DISPLAY INVISIBLE (-7475 6725);
FORCEPROP 0 LASTPIN (-7625 6275) $PN J15
J 2
(-7635 6285);
DISPLAY 0.489362 (-7635 6285);
PAINT MONO (-7635 6285);
FORCEPROP 0 LASTPIN (-7625 6225) $PN J18
J 2
(-7635 6235);
DISPLAY 0.489362 (-7635 6235);
PAINT MONO (-7635 6235);
FORCEPROP 0 LASTPIN (-7625 6175) $PN J20
J 2
(-7635 6185);
DISPLAY 0.489362 (-7635 6185);
PAINT MONO (-7635 6185);
FORCEPROP 0 LASTPIN (-7625 6125) $PN J22
J 2
(-7635 6135);
DISPLAY 0.489362 (-7635 6135);
PAINT MONO (-7635 6135);
FORCEPROP 0 LASTPIN (-7625 6075) $PN J25
J 2
(-7635 6085);
DISPLAY 0.489362 (-7635 6085);
PAINT MONO (-7635 6085);
FORCEPROP 0 LASTPIN (-7625 6025) $PN J28
J 2
(-7635 6035);
DISPLAY 0.489362 (-7635 6035);
PAINT MONO (-7635 6035);
FORCEPROP 0 LASTPIN (-7625 5975) $PN J31
J 2
(-7635 5985);
DISPLAY 0.489362 (-7635 5985);
PAINT MONO (-7635 5985);
FORCEPROP 0 LASTPIN (-7625 5925) $PN J34
J 2
(-7635 5935);
DISPLAY 0.489362 (-7635 5935);
PAINT MONO (-7635 5935);
FORCEPROP 0 LASTPIN (-7625 5875) $PN J42
J 2
(-7635 5885);
DISPLAY 0.489362 (-7635 5885);
PAINT MONO (-7635 5885);
FORCEPROP 0 LASTPIN (-7625 5825) $PN J45
J 2
(-7635 5835);
DISPLAY 0.489362 (-7635 5835);
PAINT MONO (-7635 5835);
FORCEPROP 0 LASTPIN (-7625 5775) $PN J48
J 2
(-7635 5785);
DISPLAY 0.489362 (-7635 5785);
PAINT MONO (-7635 5785);
FORCEPROP 0 LASTPIN (-7625 5725) $PN J51
J 2
(-7635 5735);
DISPLAY 0.489362 (-7635 5735);
PAINT MONO (-7635 5735);
FORCEPROP 0 LASTPIN (-7625 5675) $PN J54
J 2
(-7635 5685);
DISPLAY 0.489362 (-7635 5685);
PAINT MONO (-7635 5685);
FORCEPROP 0 LASTPIN (-7625 5625) $PN J56
J 2
(-7635 5635);
DISPLAY 0.489362 (-7635 5635);
PAINT MONO (-7635 5635);
FORCEPROP 0 LASTPIN (-7625 5575) $PN J58
J 2
(-7635 5585);
DISPLAY 0.489362 (-7635 5585);
PAINT MONO (-7635 5585);
FORCEPROP 0 LASTPIN (-7625 5525) $PN J61
J 2
(-7635 5535);
DISPLAY 0.489362 (-7635 5535);
PAINT MONO (-7635 5535);
FORCEPROP 0 LASTPIN (-7625 5475) $PN J63
J 2
(-7635 5485);
DISPLAY 0.489362 (-7635 5485);
PAINT MONO (-7635 5485);
FORCEPROP 0 LASTPIN (-7625 5425) $PN J65
J 2
(-7635 5435);
DISPLAY 0.489362 (-7635 5435);
PAINT MONO (-7635 5435);
FORCEPROP 0 LASTPIN (-7625 5375) $PN J68
J 2
(-7635 5385);
DISPLAY 0.489362 (-7635 5385);
PAINT MONO (-7635 5385);
FORCEPROP 0 LASTPIN (-7625 5325) $PN J70
J 2
(-7635 5335);
DISPLAY 0.489362 (-7635 5335);
PAINT MONO (-7635 5335);
FORCEPROP 0 LASTPIN (-7625 5275) $PN J72
J 2
(-7635 5285);
DISPLAY 0.489362 (-7635 5285);
PAINT MONO (-7635 5285);
FORCEPROP 0 LASTPIN (-7625 5225) $PN J75
J 2
(-7635 5235);
DISPLAY 0.489362 (-7635 5235);
PAINT MONO (-7635 5235);
FORCEPROP 0 LASTPIN (-7625 5175) $PN K3
J 2
(-7635 5185);
DISPLAY 0.489362 (-7635 5185);
PAINT MONO (-7635 5185);
FORCEPROP 0 LASTPIN (-7625 5125) $PN K5
J 2
(-7635 5135);
DISPLAY 0.489362 (-7635 5135);
PAINT MONO (-7635 5135);
FORCEPROP 0 LASTPIN (-7625 5075) $PN K8
J 2
(-7635 5085);
DISPLAY 0.489362 (-7635 5085);
PAINT MONO (-7635 5085);
FORCEPROP 0 LASTPIN (-7625 5025) $PN K10
J 2
(-7635 5035);
DISPLAY 0.489362 (-7635 5035);
PAINT MONO (-7635 5035);
FORCEPROP 0 LASTPIN (-7625 4975) $PN K12
J 2
(-7635 4985);
DISPLAY 0.489362 (-7635 4985);
PAINT MONO (-7635 4985);
FORCEPROP 0 LASTPIN (-7625 4925) $PN K15
J 2
(-7635 4935);
DISPLAY 0.489362 (-7635 4935);
PAINT MONO (-7635 4935);
FORCEPROP 0 LASTPIN (-7625 4875) $PN K17
J 2
(-7635 4885);
DISPLAY 0.489362 (-7635 4885);
PAINT MONO (-7635 4885);
FORCEPROP 0 LASTPIN (-7625 4825) $PN K19
J 2
(-7635 4835);
DISPLAY 0.489362 (-7635 4835);
PAINT MONO (-7635 4835);
FORCEPROP 0 LASTPIN (-7625 4775) $PN K24
J 2
(-7635 4785);
DISPLAY 0.489362 (-7635 4785);
PAINT MONO (-7635 4785);
FORCEPROP 0 LASTPIN (-7625 4725) $PN K25
J 2
(-7635 4735);
DISPLAY 0.489362 (-7635 4735);
PAINT MONO (-7635 4735);
FORCEPROP 0 LASTPIN (-7625 4675) $PN K26
J 2
(-7635 4685);
DISPLAY 0.489362 (-7635 4685);
PAINT MONO (-7635 4685);
FORCEPROP 0 LASTPIN (-7625 4625) $PN K27
J 2
(-7635 4635);
DISPLAY 0.489362 (-7635 4635);
PAINT MONO (-7635 4635);
FORCEPROP 0 LASTPIN (-7625 4575) $PN K28
J 2
(-7635 4585);
DISPLAY 0.489362 (-7635 4585);
PAINT MONO (-7635 4585);
FORCEPROP 0 LASTPIN (-7625 4525) $PN K29
J 2
(-7635 4535);
DISPLAY 0.489362 (-7635 4535);
PAINT MONO (-7635 4535);
FORCEPROP 0 LASTPIN (-7625 4475) $PN K30
J 2
(-7635 4485);
DISPLAY 0.489362 (-7635 4485);
PAINT MONO (-7635 4485);
FORCEPROP 0 LASTPIN (-7625 4425) $PN K31
J 2
(-7635 4435);
DISPLAY 0.489362 (-7635 4435);
PAINT MONO (-7635 4435);
FORCEPROP 0 LASTPIN (-7625 4375) $PN K32
J 2
(-7635 4385);
DISPLAY 0.489362 (-7635 4385);
PAINT MONO (-7635 4385);
FORCEPROP 0 LASTPIN (-7625 4325) $PN K33
J 2
(-7635 4335);
DISPLAY 0.489362 (-7635 4335);
PAINT MONO (-7635 4335);
FORCEPROP 0 LASTPIN (-7625 4275) $PN K34
J 2
(-7635 4285);
DISPLAY 0.489362 (-7635 4285);
PAINT MONO (-7635 4285);
FORCEPROP 0 LASTPIN (-7625 4225) $PN K37
J 2
(-7635 4235);
DISPLAY 0.489362 (-7635 4235);
PAINT MONO (-7635 4235);
FORCEPROP 0 LASTPIN (-7625 4175) $PN K39
J 2
(-7635 4185);
DISPLAY 0.489362 (-7635 4185);
PAINT MONO (-7635 4185);
FORCEPROP 0 LASTPIN (-7625 4125) $PN K42
J 2
(-7635 4135);
DISPLAY 0.489362 (-7635 4135);
PAINT MONO (-7635 4135);
FORCEPROP 0 LASTPIN (-7625 4075) $PN K43
J 2
(-7635 4085);
DISPLAY 0.489362 (-7635 4085);
PAINT MONO (-7635 4085);
FORCEPROP 0 LASTPIN (-7625 4025) $PN K44
J 2
(-7635 4035);
DISPLAY 0.489362 (-7635 4035);
PAINT MONO (-7635 4035);
FORCEPROP 0 LASTPIN (-7625 3975) $PN K45
J 2
(-7635 3985);
DISPLAY 0.489362 (-7635 3985);
PAINT MONO (-7635 3985);
FORCEPROP 0 LASTPIN (-7625 3925) $PN K46
J 2
(-7635 3935);
DISPLAY 0.489362 (-7635 3935);
PAINT MONO (-7635 3935);
FORCEPROP 0 LASTPIN (-7625 3875) $PN K47
J 2
(-7635 3885);
DISPLAY 0.489362 (-7635 3885);
PAINT MONO (-7635 3885);
FORCEPROP 0 LASTPIN (-7625 3825) $PN K48
J 2
(-7635 3835);
DISPLAY 0.489362 (-7635 3835);
PAINT MONO (-7635 3835);
FORCEPROP 0 LASTPIN (-7625 3775) $PN K49
J 2
(-7635 3785);
DISPLAY 0.489362 (-7635 3785);
PAINT MONO (-7635 3785);
FORCEPROP 0 LASTPIN (-7625 3725) $PN K50
J 2
(-7635 3735);
DISPLAY 0.489362 (-7635 3735);
PAINT MONO (-7635 3735);
FORCEPROP 0 LASTPIN (-7625 3675) $PN K51
J 2
(-7635 3685);
DISPLAY 0.489362 (-7635 3685);
PAINT MONO (-7635 3685);
FORCEPROP 0 LASTPIN (-7625 3625) $PN K52
J 2
(-7635 3635);
DISPLAY 0.489362 (-7635 3635);
PAINT MONO (-7635 3635);
FORCEPROP 0 LASTPIN (-7625 3575) $PN K53
J 2
(-7635 3585);
DISPLAY 0.489362 (-7635 3585);
PAINT MONO (-7635 3585);
FORCEPROP 0 LASTPIN (-7625 3525) $PN K57
J 2
(-7635 3535);
DISPLAY 0.489362 (-7635 3535);
PAINT MONO (-7635 3535);
FORCEPROP 0 LASTPIN (-7625 3475) $PN K61
J 2
(-7635 3485);
DISPLAY 0.489362 (-7635 3485);
PAINT MONO (-7635 3485);
FORCEPROP 0 LASTPIN (-7625 3425) $PN K64
J 2
(-7635 3435);
DISPLAY 0.489362 (-7635 3435);
PAINT MONO (-7635 3435);
FORCEPROP 0 LASTPIN (-7625 3375) $PN K66
J 2
(-7635 3385);
DISPLAY 0.489362 (-7635 3385);
PAINT MONO (-7635 3385);
FORCEPROP 0 LASTPIN (-7625 3325) $PN K68
J 2
(-7635 3335);
DISPLAY 0.489362 (-7635 3335);
PAINT MONO (-7635 3335);
FORCEPROP 0 LASTPIN (-7625 3275) $PN K71
J 2
(-7635 3285);
DISPLAY 0.489362 (-7635 3285);
PAINT MONO (-7635 3285);
FORCEPROP 0 LASTPIN (-7625 3225) $PN K73
J 2
(-7635 3235);
DISPLAY 0.489362 (-7635 3235);
PAINT MONO (-7635 3235);
FORCEPROP 0 LASTPIN (-7625 3175) $PN L1
J 2
(-7635 3185);
DISPLAY 0.489362 (-7635 3185);
PAINT MONO (-7635 3185);
FORCEPROP 0 LASTPIN (-7625 3125) $PN L6
J 2
(-7635 3135);
DISPLAY 0.489362 (-7635 3135);
PAINT MONO (-7635 3135);
FORCEPROP 0 LASTPIN (-7625 3075) $PN L8
J 2
(-7635 3085);
DISPLAY 0.489362 (-7635 3085);
PAINT MONO (-7635 3085);
FORCEPROP 0 LASTPIN (-7625 3025) $PN L13
J 2
(-7635 3035);
DISPLAY 0.489362 (-7635 3035);
PAINT MONO (-7635 3035);
FORCEPROP 0 LASTPIN (-7625 2975) $PN L15
J 2
(-7635 2985);
DISPLAY 0.489362 (-7635 2985);
PAINT MONO (-7635 2985);
FORCEPROP 0 LASTPIN (-7625 2925) $PN L20
J 2
(-7635 2935);
DISPLAY 0.489362 (-7635 2935);
PAINT MONO (-7635 2935);
FORCEPROP 0 LASTPIN (-7625 2875) $PN L22
J 2
(-7635 2885);
DISPLAY 0.489362 (-7635 2885);
PAINT MONO (-7635 2885);
FORCEPROP 0 LASTPIN (-7625 2825) $PN L25
J 2
(-7635 2835);
DISPLAY 0.489362 (-7635 2835);
PAINT MONO (-7635 2835);
FORCEPROP 0 LASTPIN (-7625 2775) $PN L28
J 2
(-7635 2785);
DISPLAY 0.489362 (-7635 2785);
PAINT MONO (-7635 2785);
FORCEPROP 0 LASTPIN (-7625 2725) $PN L31
J 2
(-7635 2735);
DISPLAY 0.489362 (-7635 2735);
PAINT MONO (-7635 2735);
FORCEPROP 0 LASTPIN (-7625 2675) $PN L34
J 2
(-7635 2685);
DISPLAY 0.489362 (-7635 2685);
PAINT MONO (-7635 2685);
FORCEPROP 0 LASTPIN (-7625 2625) $PN L35
J 2
(-7635 2635);
DISPLAY 0.489362 (-7635 2635);
PAINT MONO (-7635 2635);
FORCEPROP 0 LASTPIN (-7625 2575) $PN L36
J 2
(-7635 2585);
DISPLAY 0.489362 (-7635 2585);
PAINT MONO (-7635 2585);
FORCEPROP 0 LASTPIN (-7625 2525) $PN L40
J 2
(-7635 2535);
DISPLAY 0.489362 (-7635 2535);
PAINT MONO (-7635 2535);
FORCEPROP 0 LASTPIN (-7625 2475) $PN L41
J 2
(-7635 2485);
DISPLAY 0.489362 (-7635 2485);
PAINT MONO (-7635 2485);
FORCEPROP 0 LASTPIN (-7625 2425) $PN L42
J 2
(-7635 2435);
DISPLAY 0.489362 (-7635 2435);
PAINT MONO (-7635 2435);
FORCEPROP 0 LASTPIN (-7625 2375) $PN L45
J 2
(-7635 2385);
DISPLAY 0.489362 (-7635 2385);
PAINT MONO (-7635 2385);
FORCEPROP 0 LASTPIN (-7625 2325) $PN L48
J 2
(-7635 2335);
DISPLAY 0.489362 (-7635 2335);
PAINT MONO (-7635 2335);
FORCEPROP 0 LASTPIN (-7625 2275) $PN L51
J 2
(-7635 2285);
DISPLAY 0.489362 (-7635 2285);
PAINT MONO (-7635 2285);
FORCEPROP 0 LASTPIN (-7625 2225) $PN L54
J 2
(-7635 2235);
DISPLAY 0.489362 (-7635 2235);
PAINT MONO (-7635 2235);
FORCEPROP 0 LASTPIN (-7625 2175) $PN L56
J 2
(-7635 2185);
DISPLAY 0.489362 (-7635 2185);
PAINT MONO (-7635 2185);
FORCEPROP 0 LASTPIN (-7625 2125) $PN L61
J 2
(-7635 2135);
DISPLAY 0.489362 (-7635 2135);
PAINT MONO (-7635 2135);
FORCEPROP 0 LASTPIN (-7625 2075) $PN L63
J 2
(-7635 2085);
DISPLAY 0.489362 (-7635 2085);
PAINT MONO (-7635 2085);
FORCEPROP 0 LASTPIN (-7625 2025) $PN L68
J 2
(-7635 2035);
DISPLAY 0.489362 (-7635 2035);
PAINT MONO (-7635 2035);
FORCEPROP 0 LASTPIN (-7625 1975) $PN L70
J 2
(-7635 1985);
DISPLAY 0.489362 (-7635 1985);
PAINT MONO (-7635 1985);
FORCEPROP 0 LASTPIN (-7625 1925) $PN L75
J 2
(-7635 1935);
DISPLAY 0.489362 (-7635 1935);
PAINT MONO (-7635 1935);
FORCEPROP 0 LASTPIN (-7625 1875) $PN M3
J 2
(-7635 1885);
DISPLAY 0.489362 (-7635 1885);
PAINT MONO (-7635 1885);
FORCEPROP 0 LASTPIN (-7625 1825) $PN M5
J 2
(-7635 1835);
DISPLAY 0.489362 (-7635 1835);
PAINT MONO (-7635 1835);
FORCEPROP 0 LASTPIN (-7625 1775) $PN M8
J 2
(-7635 1785);
DISPLAY 0.489362 (-7635 1785);
PAINT MONO (-7635 1785);
FORCEPROP 0 LASTPIN (-7625 1725) $PN M10
J 2
(-7635 1735);
DISPLAY 0.489362 (-7635 1735);
PAINT MONO (-7635 1735);
FORCEPROP 0 LASTPIN (-7625 1675) $PN M12
J 2
(-7635 1685);
DISPLAY 0.489362 (-7635 1685);
PAINT MONO (-7635 1685);
FORCEPROP 0 LASTPIN (-7625 1625) $PN M15
J 2
(-7635 1635);
DISPLAY 0.489362 (-7635 1635);
PAINT MONO (-7635 1635);
FORCEPROP 0 LASTPIN (-7625 1575) $PN M17
J 2
(-7635 1585);
DISPLAY 0.489362 (-7635 1585);
PAINT MONO (-7635 1585);
FORCEPROP 0 LASTPIN (-7625 1525) $PN M19
J 2
(-7635 1535);
DISPLAY 0.489362 (-7635 1535);
PAINT MONO (-7635 1535);
FORCEPROP 0 LASTPIN (-7625 1475) $PN M22
J 2
(-7635 1485);
DISPLAY 0.489362 (-7635 1485);
PAINT MONO (-7635 1485);
FORCEPROP 0 LASTPIN (-7625 1425) $PN M25
J 2
(-7635 1435);
DISPLAY 0.489362 (-7635 1435);
PAINT MONO (-7635 1435);
FORCEPROP 0 LASTPIN (-7625 1375) $PN M28
J 2
(-7635 1385);
DISPLAY 0.489362 (-7635 1385);
PAINT MONO (-7635 1385);
FORCEPROP 0 LASTPIN (-7625 1325) $PN M31
J 2
(-7635 1335);
DISPLAY 0.489362 (-7635 1335);
PAINT MONO (-7635 1335);
FORCEPROP 0 LASTPIN (-7625 1275) $PN M34
J 2
(-7635 1285);
DISPLAY 0.489362 (-7635 1285);
PAINT MONO (-7635 1285);
FORCEPROP 0 LASTPIN (-7625 1225) $PN M37
J 2
(-7635 1235);
DISPLAY 0.489362 (-7635 1235);
PAINT MONO (-7635 1235);
FORCEPROP 0 LASTPIN (-7625 1175) $PN M39
J 2
(-7635 1185);
DISPLAY 0.489362 (-7635 1185);
PAINT MONO (-7635 1185);
FORCEPROP 0 LASTPIN (-7625 1125) $PN M42
J 2
(-7635 1135);
DISPLAY 0.489362 (-7635 1135);
PAINT MONO (-7635 1135);
FORCEPROP 0 LASTPIN (-7625 1075) $PN M45
J 2
(-7635 1085);
DISPLAY 0.489362 (-7635 1085);
PAINT MONO (-7635 1085);
FORCEPROP 0 LASTPIN (-7625 1025) $PN M48
J 2
(-7635 1035);
DISPLAY 0.489362 (-7635 1035);
PAINT MONO (-7635 1035);
FORCEPROP 0 LASTPIN (-7625 975) $PN M51
J 2
(-7635 985);
DISPLAY 0.489362 (-7635 985);
PAINT MONO (-7635 985);
FORCEPROP 0 LASTPIN (-7625 925) $PN M54
J 2
(-7635 935);
DISPLAY 0.489362 (-7635 935);
PAINT MONO (-7635 935);
FORCEPROP 0 LASTPIN (-7625 875) $PN M57
J 2
(-7635 885);
DISPLAY 0.489362 (-7635 885);
PAINT MONO (-7635 885);
FORCEPROP 0 LASTPIN (-7625 825) $PN M59
J 2
(-7635 835);
DISPLAY 0.489362 (-7635 835);
PAINT MONO (-7635 835);
FORCEPROP 0 LASTPIN (-7625 775) $PN M61
J 2
(-7635 785);
DISPLAY 0.489362 (-7635 785);
PAINT MONO (-7635 785);
FORCEPROP 0 LASTPIN (-7625 725) $PN M64
J 2
(-7635 735);
DISPLAY 0.489362 (-7635 735);
PAINT MONO (-7635 735);
FORCEPROP 0 LASTPIN (-7625 675) $PN M66
J 2
(-7635 685);
DISPLAY 0.489362 (-7635 685);
PAINT MONO (-7635 685);
FORCEPROP 0 LASTPIN (-7625 625) $PN M68
J 2
(-7635 635);
DISPLAY 0.489362 (-7635 635);
PAINT MONO (-7635 635);
FORCEPROP 0 LASTPIN (-7625 575) $PN M71
J 2
(-7635 585);
DISPLAY 0.489362 (-7635 585);
PAINT MONO (-7635 585);
FORCEPROP 0 LASTPIN (-7625 525) $PN M73
J 2
(-7635 535);
DISPLAY 0.489362 (-7635 535);
PAINT MONO (-7635 535);
FORCEPROP 0 LASTPIN (-7625 475) $PN N1
J 2
(-7635 485);
DISPLAY 0.489362 (-7635 485);
PAINT MONO (-7635 485);
FORCEPROP 0 LASTPIN (-6525 6275) $PN N4
J 0
(-6515 6285);
DISPLAY 0.489362 (-6515 6285);
PAINT MONO (-6515 6285);
FORCEPROP 0 LASTPIN (-6525 6225) $PN N6
J 0
(-6515 6235);
DISPLAY 0.489362 (-6515 6235);
PAINT MONO (-6515 6235);
FORCEPROP 0 LASTPIN (-6525 6175) $PN N8
J 0
(-6515 6185);
DISPLAY 0.489362 (-6515 6185);
PAINT MONO (-6515 6185);
FORCEPROP 0 LASTPIN (-6525 6125) $PN N11
J 0
(-6515 6135);
DISPLAY 0.489362 (-6515 6135);
PAINT MONO (-6515 6135);
FORCEPROP 0 LASTPIN (-6525 6075) $PN N13
J 0
(-6515 6085);
DISPLAY 0.489362 (-6515 6085);
PAINT MONO (-6515 6085);
FORCEPROP 0 LASTPIN (-6525 6025) $PN N15
J 0
(-6515 6035);
DISPLAY 0.489362 (-6515 6035);
PAINT MONO (-6515 6035);
FORCEPROP 0 LASTPIN (-6525 5975) $PN N18
J 0
(-6515 5985);
DISPLAY 0.489362 (-6515 5985);
PAINT MONO (-6515 5985);
FORCEPROP 0 LASTPIN (-6525 5925) $PN N20
J 0
(-6515 5935);
DISPLAY 0.489362 (-6515 5935);
PAINT MONO (-6515 5935);
FORCEPROP 0 LASTPIN (-6525 5875) $PN N22
J 0
(-6515 5885);
DISPLAY 0.489362 (-6515 5885);
PAINT MONO (-6515 5885);
FORCEPROP 0 LASTPIN (-6525 5825) $PN N25
J 0
(-6515 5835);
DISPLAY 0.489362 (-6515 5835);
PAINT MONO (-6515 5835);
FORCEPROP 0 LASTPIN (-6525 5775) $PN N28
J 0
(-6515 5785);
DISPLAY 0.489362 (-6515 5785);
PAINT MONO (-6515 5785);
FORCEPROP 0 LASTPIN (-6525 5725) $PN N31
J 0
(-6515 5735);
DISPLAY 0.489362 (-6515 5735);
PAINT MONO (-6515 5735);
FORCEPROP 0 LASTPIN (-6525 5675) $PN N34
J 0
(-6515 5685);
DISPLAY 0.489362 (-6515 5685);
PAINT MONO (-6515 5685);
FORCEPROP 0 LASTPIN (-6525 5625) $PN N42
J 0
(-6515 5635);
DISPLAY 0.489362 (-6515 5635);
PAINT MONO (-6515 5635);
FORCEPROP 0 LASTPIN (-6525 5575) $PN N45
J 0
(-6515 5585);
DISPLAY 0.489362 (-6515 5585);
PAINT MONO (-6515 5585);
FORCEPROP 0 LASTPIN (-6525 5525) $PN N48
J 0
(-6515 5535);
DISPLAY 0.489362 (-6515 5535);
PAINT MONO (-6515 5535);
FORCEPROP 0 LASTPIN (-6525 5475) $PN N51
J 0
(-6515 5485);
DISPLAY 0.489362 (-6515 5485);
PAINT MONO (-6515 5485);
FORCEPROP 0 LASTPIN (-6525 5425) $PN N54
J 0
(-6515 5435);
DISPLAY 0.489362 (-6515 5435);
PAINT MONO (-6515 5435);
FORCEPROP 0 LASTPIN (-6525 5375) $PN N56
J 0
(-6515 5385);
DISPLAY 0.489362 (-6515 5385);
PAINT MONO (-6515 5385);
FORCEPROP 0 LASTPIN (-6525 5325) $PN N58
J 0
(-6515 5335);
DISPLAY 0.489362 (-6515 5335);
PAINT MONO (-6515 5335);
FORCEPROP 0 LASTPIN (-6525 5275) $PN N61
J 0
(-6515 5285);
DISPLAY 0.489362 (-6515 5285);
PAINT MONO (-6515 5285);
FORCEPROP 0 LASTPIN (-6525 5225) $PN N63
J 0
(-6515 5235);
DISPLAY 0.489362 (-6515 5235);
PAINT MONO (-6515 5235);
FORCEPROP 0 LASTPIN (-6525 5175) $PN N65
J 0
(-6515 5185);
DISPLAY 0.489362 (-6515 5185);
PAINT MONO (-6515 5185);
FORCEPROP 0 LASTPIN (-6525 5125) $PN N68
J 0
(-6515 5135);
DISPLAY 0.489362 (-6515 5135);
PAINT MONO (-6515 5135);
FORCEPROP 0 LASTPIN (-6525 5075) $PN N70
J 0
(-6515 5085);
DISPLAY 0.489362 (-6515 5085);
PAINT MONO (-6515 5085);
FORCEPROP 0 LASTPIN (-6525 5025) $PN N72
J 0
(-6515 5035);
DISPLAY 0.489362 (-6515 5035);
PAINT MONO (-6515 5035);
FORCEPROP 0 LASTPIN (-6525 4975) $PN N75
J 0
(-6515 4985);
DISPLAY 0.489362 (-6515 4985);
PAINT MONO (-6515 4985);
FORCEPROP 0 LASTPIN (-6525 4925) $PN P3
J 0
(-6515 4935);
DISPLAY 0.489362 (-6515 4935);
PAINT MONO (-6515 4935);
FORCEPROP 0 LASTPIN (-6525 4875) $PN P8
J 0
(-6515 4885);
DISPLAY 0.489362 (-6515 4885);
PAINT MONO (-6515 4885);
FORCEPROP 0 LASTPIN (-6525 4825) $PN P10
J 0
(-6515 4835);
DISPLAY 0.489362 (-6515 4835);
PAINT MONO (-6515 4835);
FORCEPROP 0 LASTPIN (-6525 4775) $PN P15
J 0
(-6515 4785);
DISPLAY 0.489362 (-6515 4785);
PAINT MONO (-6515 4785);
FORCEPROP 0 LASTPIN (-6525 4725) $PN P17
J 0
(-6515 4735);
DISPLAY 0.489362 (-6515 4735);
PAINT MONO (-6515 4735);
FORCEPROP 0 LASTPIN (-6525 4675) $PN P23
J 0
(-6515 4685);
DISPLAY 0.489362 (-6515 4685);
PAINT MONO (-6515 4685);
FORCEPROP 0 LASTPIN (-6525 4625) $PN P24
J 0
(-6515 4635);
DISPLAY 0.489362 (-6515 4635);
PAINT MONO (-6515 4635);
FORCEPROP 0 LASTPIN (-6525 4575) $PN P26
J 0
(-6515 4585);
DISPLAY 0.489362 (-6515 4585);
PAINT MONO (-6515 4585);
FORCEPROP 0 LASTPIN (-6525 4525) $PN P27
J 0
(-6515 4535);
DISPLAY 0.489362 (-6515 4535);
PAINT MONO (-6515 4535);
FORCEPROP 0 LASTPIN (-6525 4475) $PN P28
J 0
(-6515 4485);
DISPLAY 0.489362 (-6515 4485);
PAINT MONO (-6515 4485);
FORCEPROP 0 LASTPIN (-6525 4425) $PN P29
J 0
(-6515 4435);
DISPLAY 0.489362 (-6515 4435);
PAINT MONO (-6515 4435);
FORCEPROP 0 LASTPIN (-6525 4375) $PN P30
J 0
(-6515 4385);
DISPLAY 0.489362 (-6515 4385);
PAINT MONO (-6515 4385);
FORCEPROP 0 LASTPIN (-6525 4325) $PN P31
J 0
(-6515 4335);
DISPLAY 0.489362 (-6515 4335);
PAINT MONO (-6515 4335);
FORCEPROP 0 LASTPIN (-6525 4275) $PN P32
J 0
(-6515 4285);
DISPLAY 0.489362 (-6515 4285);
PAINT MONO (-6515 4285);
FORCEPROP 0 LASTPIN (-6525 4225) $PN P33
J 0
(-6515 4235);
DISPLAY 0.489362 (-6515 4235);
PAINT MONO (-6515 4235);
FORCEPROP 0 LASTPIN (-6525 4175) $PN P34
J 0
(-6515 4185);
DISPLAY 0.489362 (-6515 4185);
PAINT MONO (-6515 4185);
FORCEPROP 0 LASTPIN (-6525 4125) $PN P37
J 0
(-6515 4135);
DISPLAY 0.489362 (-6515 4135);
PAINT MONO (-6515 4135);
FORCEPROP 0 LASTPIN (-6525 4075) $PN P39
J 0
(-6515 4085);
DISPLAY 0.489362 (-6515 4085);
PAINT MONO (-6515 4085);
FORCEPROP 0 LASTPIN (-6525 4025) $PN P42
J 0
(-6515 4035);
DISPLAY 0.489362 (-6515 4035);
PAINT MONO (-6515 4035);
FORCEPROP 0 LASTPIN (-6525 3975) $PN P43
J 0
(-6515 3985);
DISPLAY 0.489362 (-6515 3985);
PAINT MONO (-6515 3985);
FORCEPROP 0 LASTPIN (-6525 3925) $PN P44
J 0
(-6515 3935);
DISPLAY 0.489362 (-6515 3935);
PAINT MONO (-6515 3935);
FORCEPROP 0 LASTPIN (-6525 3875) $PN P45
J 0
(-6515 3885);
DISPLAY 0.489362 (-6515 3885);
PAINT MONO (-6515 3885);
FORCEPROP 0 LASTPIN (-6525 3825) $PN P46
J 0
(-6515 3835);
DISPLAY 0.489362 (-6515 3835);
PAINT MONO (-6515 3835);
FORCEPROP 0 LASTPIN (-6525 3775) $PN P47
J 0
(-6515 3785);
DISPLAY 0.489362 (-6515 3785);
PAINT MONO (-6515 3785);
FORCEPROP 0 LASTPIN (-6525 3725) $PN P48
J 0
(-6515 3735);
DISPLAY 0.489362 (-6515 3735);
PAINT MONO (-6515 3735);
FORCEPROP 0 LASTPIN (-6525 3675) $PN P49
J 0
(-6515 3685);
DISPLAY 0.489362 (-6515 3685);
PAINT MONO (-6515 3685);
FORCEPROP 0 LASTPIN (-6525 3625) $PN P50
J 0
(-6515 3635);
DISPLAY 0.489362 (-6515 3635);
PAINT MONO (-6515 3635);
FORCEPROP 0 LASTPIN (-6525 3575) $PN P51
J 0
(-6515 3585);
DISPLAY 0.489362 (-6515 3585);
PAINT MONO (-6515 3585);
FORCEPROP 0 LASTPIN (-6525 3525) $PN P52
J 0
(-6515 3535);
DISPLAY 0.489362 (-6515 3535);
PAINT MONO (-6515 3535);
FORCEPROP 0 LASTPIN (-6525 3475) $PN P53
J 0
(-6515 3485);
DISPLAY 0.489362 (-6515 3485);
PAINT MONO (-6515 3485);
FORCEPROP 0 LASTPIN (-6525 3425) $PN P59
J 0
(-6515 3435);
DISPLAY 0.489362 (-6515 3435);
PAINT MONO (-6515 3435);
FORCEPROP 0 LASTPIN (-6525 3375) $PN P61
J 0
(-6515 3385);
DISPLAY 0.489362 (-6515 3385);
PAINT MONO (-6515 3385);
FORCEPROP 0 LASTPIN (-6525 3325) $PN P66
J 0
(-6515 3335);
DISPLAY 0.489362 (-6515 3335);
PAINT MONO (-6515 3335);
FORCEPROP 0 LASTPIN (-6525 3275) $PN P73
J 0
(-6515 3285);
DISPLAY 0.489362 (-6515 3285);
PAINT MONO (-6515 3285);
FORCEPROP 0 LASTPIN (-6525 3225) $PN R1
J 0
(-6515 3235);
DISPLAY 0.489362 (-6515 3235);
PAINT MONO (-6515 3235);
FORCEPROP 0 LASTPIN (-6525 3175) $PN R4
J 0
(-6515 3185);
DISPLAY 0.489362 (-6515 3185);
PAINT MONO (-6515 3185);
FORCEPROP 0 LASTPIN (-6525 3125) $PN R6
J 0
(-6515 3135);
DISPLAY 0.489362 (-6515 3135);
PAINT MONO (-6515 3135);
FORCEPROP 0 LASTPIN (-6525 3075) $PN R8
J 0
(-6515 3085);
DISPLAY 0.489362 (-6515 3085);
PAINT MONO (-6515 3085);
FORCEPROP 0 LASTPIN (-6525 3025) $PN R11
J 0
(-6515 3035);
DISPLAY 0.489362 (-6515 3035);
PAINT MONO (-6515 3035);
FORCEPROP 0 LASTPIN (-6525 2975) $PN R13
J 0
(-6515 2985);
DISPLAY 0.489362 (-6515 2985);
PAINT MONO (-6515 2985);
FORCEPROP 0 LASTPIN (-6525 2925) $PN R15
J 0
(-6515 2935);
DISPLAY 0.489362 (-6515 2935);
PAINT MONO (-6515 2935);
FORCEPROP 0 LASTPIN (-6525 2875) $PN R18
J 0
(-6515 2885);
DISPLAY 0.489362 (-6515 2885);
PAINT MONO (-6515 2885);
FORCEPROP 0 LASTPIN (-6525 2825) $PN R20
J 0
(-6515 2835);
DISPLAY 0.489362 (-6515 2835);
PAINT MONO (-6515 2835);
FORCEPROP 0 LASTPIN (-6525 2775) $PN R22
J 0
(-6515 2785);
DISPLAY 0.489362 (-6515 2785);
PAINT MONO (-6515 2785);
FORCEPROP 0 LASTPIN (-6525 2725) $PN R25
J 0
(-6515 2735);
DISPLAY 0.489362 (-6515 2735);
PAINT MONO (-6515 2735);
FORCEPROP 0 LASTPIN (-6525 2675) $PN R28
J 0
(-6515 2685);
DISPLAY 0.489362 (-6515 2685);
PAINT MONO (-6515 2685);
FORCEPROP 0 LASTPIN (-6525 2625) $PN R31
J 0
(-6515 2635);
DISPLAY 0.489362 (-6515 2635);
PAINT MONO (-6515 2635);
FORCEPROP 0 LASTPIN (-6525 2575) $PN R34
J 0
(-6515 2585);
DISPLAY 0.489362 (-6515 2585);
PAINT MONO (-6515 2585);
FORCEPROP 0 LASTPIN (-6525 2525) $PN R35
J 0
(-6515 2535);
DISPLAY 0.489362 (-6515 2535);
PAINT MONO (-6515 2535);
FORCEPROP 0 LASTPIN (-6525 2475) $PN R36
J 0
(-6515 2485);
DISPLAY 0.489362 (-6515 2485);
PAINT MONO (-6515 2485);
FORCEPROP 0 LASTPIN (-6525 2425) $PN R40
J 0
(-6515 2435);
DISPLAY 0.489362 (-6515 2435);
PAINT MONO (-6515 2435);
FORCEPROP 0 LASTPIN (-6525 2375) $PN R41
J 0
(-6515 2385);
DISPLAY 0.489362 (-6515 2385);
PAINT MONO (-6515 2385);
FORCEPROP 0 LASTPIN (-6525 2325) $PN R42
J 0
(-6515 2335);
DISPLAY 0.489362 (-6515 2335);
PAINT MONO (-6515 2335);
FORCEPROP 0 LASTPIN (-6525 2275) $PN R45
J 0
(-6515 2285);
DISPLAY 0.489362 (-6515 2285);
PAINT MONO (-6515 2285);
FORCEPROP 0 LASTPIN (-6525 2225) $PN R48
J 0
(-6515 2235);
DISPLAY 0.489362 (-6515 2235);
PAINT MONO (-6515 2235);
FORCEPROP 0 LASTPIN (-6525 2175) $PN R51
J 0
(-6515 2185);
DISPLAY 0.489362 (-6515 2185);
PAINT MONO (-6515 2185);
FORCEPROP 0 LASTPIN (-6525 2125) $PN R54
J 0
(-6515 2135);
DISPLAY 0.489362 (-6515 2135);
PAINT MONO (-6515 2135);
FORCEPROP 0 LASTPIN (-6525 2075) $PN R56
J 0
(-6515 2085);
DISPLAY 0.489362 (-6515 2085);
PAINT MONO (-6515 2085);
FORCEPROP 0 LASTPIN (-6525 2025) $PN R58
J 0
(-6515 2035);
DISPLAY 0.489362 (-6515 2035);
PAINT MONO (-6515 2035);
FORCEPROP 0 LASTPIN (-6525 1975) $PN R61
J 0
(-6515 1985);
DISPLAY 0.489362 (-6515 1985);
PAINT MONO (-6515 1985);
FORCEPROP 0 LASTPIN (-6525 1925) $PN R63
J 0
(-6515 1935);
DISPLAY 0.489362 (-6515 1935);
PAINT MONO (-6515 1935);
FORCEPROP 0 LASTPIN (-6525 1875) $PN R65
J 0
(-6515 1885);
DISPLAY 0.489362 (-6515 1885);
PAINT MONO (-6515 1885);
FORCEPROP 0 LASTPIN (-6525 1825) $PN R68
J 0
(-6515 1835);
DISPLAY 0.489362 (-6515 1835);
PAINT MONO (-6515 1835);
FORCEPROP 0 LASTPIN (-6525 1775) $PN R70
J 0
(-6515 1785);
DISPLAY 0.489362 (-6515 1785);
PAINT MONO (-6515 1785);
FORCEPROP 0 LASTPIN (-6525 1725) $PN R72
J 0
(-6515 1735);
DISPLAY 0.489362 (-6515 1735);
PAINT MONO (-6515 1735);
FORCEPROP 0 LASTPIN (-6525 1675) $PN R75
J 0
(-6515 1685);
DISPLAY 0.489362 (-6515 1685);
PAINT MONO (-6515 1685);
FORCEPROP 0 LASTPIN (-6525 1625) $PN T3
J 0
(-6515 1635);
DISPLAY 0.489362 (-6515 1635);
PAINT MONO (-6515 1635);
FORCEPROP 0 LASTPIN (-6525 1575) $PN T5
J 0
(-6515 1585);
DISPLAY 0.489362 (-6515 1585);
PAINT MONO (-6515 1585);
FORCEPROP 0 LASTPIN (-6525 1525) $PN T8
J 0
(-6515 1535);
DISPLAY 0.489362 (-6515 1535);
PAINT MONO (-6515 1535);
FORCEPROP 0 LASTPIN (-6525 1475) $PN T10
J 0
(-6515 1485);
DISPLAY 0.489362 (-6515 1485);
PAINT MONO (-6515 1485);
FORCEPROP 0 LASTPIN (-6525 1425) $PN T12
J 0
(-6515 1435);
DISPLAY 0.489362 (-6515 1435);
PAINT MONO (-6515 1435);
FORCEPROP 0 LASTPIN (-6525 1375) $PN T15
J 0
(-6515 1385);
DISPLAY 0.489362 (-6515 1385);
PAINT MONO (-6515 1385);
FORCEPROP 0 LASTPIN (-6525 1325) $PN T17
J 0
(-6515 1335);
DISPLAY 0.489362 (-6515 1335);
PAINT MONO (-6515 1335);
FORCEPROP 0 LASTPIN (-6525 1275) $PN T19
J 0
(-6515 1285);
DISPLAY 0.489362 (-6515 1285);
PAINT MONO (-6515 1285);
FORCEPROP 0 LASTPIN (-6525 1225) $PN T22
J 0
(-6515 1235);
DISPLAY 0.489362 (-6515 1235);
PAINT MONO (-6515 1235);
FORCEPROP 0 LASTPIN (-6525 1175) $PN T25
J 0
(-6515 1185);
DISPLAY 0.489362 (-6515 1185);
PAINT MONO (-6515 1185);
FORCEPROP 0 LASTPIN (-6525 1125) $PN T28
J 0
(-6515 1135);
DISPLAY 0.489362 (-6515 1135);
PAINT MONO (-6515 1135);
FORCEPROP 0 LASTPIN (-6525 1075) $PN T31
J 0
(-6515 1085);
DISPLAY 0.489362 (-6515 1085);
PAINT MONO (-6515 1085);
FORCEPROP 0 LASTPIN (-6525 1025) $PN T34
J 0
(-6515 1035);
DISPLAY 0.489362 (-6515 1035);
PAINT MONO (-6515 1035);
FORCEPROP 0 LASTPIN (-6525 975) $PN T37
J 0
(-6515 985);
DISPLAY 0.489362 (-6515 985);
PAINT MONO (-6515 985);
FORCEPROP 0 LASTPIN (-6525 925) $PN T39
J 0
(-6515 935);
DISPLAY 0.489362 (-6515 935);
PAINT MONO (-6515 935);
FORCEPROP 0 LASTPIN (-6525 875) $PN T42
J 0
(-6515 885);
DISPLAY 0.489362 (-6515 885);
PAINT MONO (-6515 885);
FORCEPROP 0 LASTPIN (-6525 825) $PN T45
J 0
(-6515 835);
DISPLAY 0.489362 (-6515 835);
PAINT MONO (-6515 835);
FORCEPROP 0 LASTPIN (-6525 775) $PN T48
J 0
(-6515 785);
DISPLAY 0.489362 (-6515 785);
PAINT MONO (-6515 785);
FORCEPROP 0 LASTPIN (-6525 725) $PN T51
J 0
(-6515 735);
DISPLAY 0.489362 (-6515 735);
PAINT MONO (-6515 735);
FORCEPROP 0 LASTPIN (-6525 675) $PN T54
J 0
(-6515 685);
DISPLAY 0.489362 (-6515 685);
PAINT MONO (-6515 685);
FORCEPROP 0 LASTPIN (-6525 625) $PN T57
J 0
(-6515 635);
DISPLAY 0.489362 (-6515 635);
PAINT MONO (-6515 635);
FORCEPROP 0 LASTPIN (-6525 575) $PN T59
J 0
(-6515 585);
DISPLAY 0.489362 (-6515 585);
PAINT MONO (-6515 585);
FORCEPROP 0 LASTPIN (-6525 525) $PN T61
J 0
(-6515 535);
DISPLAY 0.489362 (-6515 535);
PAINT MONO (-6515 535);
FORCEPROP 0 LASTPIN (-6525 475) $PN T64
J 0
(-6515 485);
DISPLAY 0.489362 (-6515 485);
PAINT MONO (-6515 485);
FORCEPROP 2 LAST PART_TYPE SMLF
J 0
(-7475 6700);
DISPLAY 1.021277 (-7475 6700);
FORCEPROP 1 LAST MATERIAL IO
J 0
(-7470 6507);
DISPLAY 0.489362 (-7470 6507);
PAINT SKYBLUE (-7470 6507);
FORCEPROP 2 LAST VALUE SOCKET6096_13568-001
J 0
(-7475 6555);
DISPLAY 0.489362 (-7475 6555);
PAINT SKYBLUE (-7475 6555);
FORCEPROP 1 LAST NEEDS_NO_SIZE TRUE
J 0
(-7075 3425);
DISPLAY 0.723404 (-7075 3425);
PAINT GREEN (-7075 3425);
DISPLAY INVISIBLE (-7075 3425);
FORCEPROP 1 LAST CDS_LMAN_SYM_OUTLINE -400,3050,400,-3050
J 0
(-7075 3425);
DISPLAY 0.468085 (-7075 3425);
PAINT GREEN (-7075 3425);
DISPLAY INVISIBLE (-7075 3425);
FORCEPROP 2 LAST CDS_LIB pure_quanta
J 0
(-7075 3425);
DISPLAY INVISIBLE (-7075 3425);
FORCEPROP 1 LAST PATH I20
J 0
(-7075 3425);
DISPLAY 0.723404 (-7075 3425);
PAINT GREEN (-7075 3425);
DISPLAY INVISIBLE (-7075 3425);
FORCEPROP 1 LAST PART_NUMBER DGA^6000030
J 0
(-7470 6650);
DISPLAY 0.489362 (-7470 6650);
PAINT SKYBLUE (-7470 6650);
DISPLAY INVISIBLE (-7470 6650);
FORCEADD GENOA_SP5..30
(-5600 3450);
FORCEPROP 1 LAST LOCATION U25
J 0
(-5995 6600);
DISPLAY 0.489362 (-5995 6600);
PAINT SKYBLUE (-5995 6600);
FORCEPROP 0 LAST $SEC 30
J 0
(-5975 6850);
DISPLAY 0.680851 (-5975 6850);
PAINT MONO (-5975 6850);
DISPLAY INVISIBLE (-5975 6850);
FORCEPROP 0 LAST CDS_SEC 30
J 0
(-6000 6725);
DISPLAY 1.021277 (-6000 6725);
DISPLAY INVISIBLE (-6000 6725);
FORCEPROP 0 LASTPIN (-5050 5600) $PN AA1
J 0
(-5040 5610);
DISPLAY 0.489362 (-5040 5610);
PAINT MONO (-5040 5610);
FORCEPROP 0 LASTPIN (-5050 5550) $PN AA4
J 0
(-5040 5560);
DISPLAY 0.489362 (-5040 5560);
PAINT MONO (-5040 5560);
FORCEPROP 0 LASTPIN (-5050 5500) $PN AA6
J 0
(-5040 5510);
DISPLAY 0.489362 (-5040 5510);
PAINT MONO (-5040 5510);
FORCEPROP 0 LASTPIN (-5050 5450) $PN AA8
J 0
(-5040 5460);
DISPLAY 0.489362 (-5040 5460);
PAINT MONO (-5040 5460);
FORCEPROP 0 LASTPIN (-5050 5400) $PN AA11
J 0
(-5040 5410);
DISPLAY 0.489362 (-5040 5410);
PAINT MONO (-5040 5410);
FORCEPROP 0 LASTPIN (-5050 5350) $PN AA13
J 0
(-5040 5360);
DISPLAY 0.489362 (-5040 5360);
PAINT MONO (-5040 5360);
FORCEPROP 0 LASTPIN (-5050 5300) $PN AA15
J 0
(-5040 5310);
DISPLAY 0.489362 (-5040 5310);
PAINT MONO (-5040 5310);
FORCEPROP 0 LASTPIN (-5050 5250) $PN AA18
J 0
(-5040 5260);
DISPLAY 0.489362 (-5040 5260);
PAINT MONO (-5040 5260);
FORCEPROP 0 LASTPIN (-5050 5200) $PN AA20
J 0
(-5040 5210);
DISPLAY 0.489362 (-5040 5210);
PAINT MONO (-5040 5210);
FORCEPROP 0 LASTPIN (-5050 5150) $PN AA31
J 0
(-5040 5160);
DISPLAY 0.489362 (-5040 5160);
PAINT MONO (-5040 5160);
FORCEPROP 0 LASTPIN (-5050 5100) $PN AA34
J 0
(-5040 5110);
DISPLAY 0.489362 (-5040 5110);
PAINT MONO (-5040 5110);
FORCEPROP 0 LASTPIN (-5050 5050) $PN AA35
J 0
(-5040 5060);
DISPLAY 0.489362 (-5040 5060);
PAINT MONO (-5040 5060);
FORCEPROP 0 LASTPIN (-5050 5000) $PN AA36
J 0
(-5040 5010);
DISPLAY 0.489362 (-5040 5010);
PAINT MONO (-5040 5010);
FORCEPROP 0 LASTPIN (-5050 4950) $PN AA40
J 0
(-5040 4960);
DISPLAY 0.489362 (-5040 4960);
PAINT MONO (-5040 4960);
FORCEPROP 0 LASTPIN (-5050 4900) $PN AA41
J 0
(-5040 4910);
DISPLAY 0.489362 (-5040 4910);
PAINT MONO (-5040 4910);
FORCEPROP 0 LASTPIN (-5050 4850) $PN AA45
J 0
(-5040 4860);
DISPLAY 0.489362 (-5040 4860);
PAINT MONO (-5040 4860);
FORCEPROP 0 LASTPIN (-5050 4800) $PN AA56
J 0
(-5040 4810);
DISPLAY 0.489362 (-5040 4810);
PAINT MONO (-5040 4810);
FORCEPROP 0 LASTPIN (-5050 4750) $PN AA58
J 0
(-5040 4760);
DISPLAY 0.489362 (-5040 4760);
PAINT MONO (-5040 4760);
FORCEPROP 0 LASTPIN (-5050 4700) $PN AA61
J 0
(-5040 4710);
DISPLAY 0.489362 (-5040 4710);
PAINT MONO (-5040 4710);
FORCEPROP 0 LASTPIN (-5050 4650) $PN AA63
J 0
(-5040 4660);
DISPLAY 0.489362 (-5040 4660);
PAINT MONO (-5040 4660);
FORCEPROP 0 LASTPIN (-5050 4600) $PN AA65
J 0
(-5040 4610);
DISPLAY 0.489362 (-5040 4610);
PAINT MONO (-5040 4610);
FORCEPROP 0 LASTPIN (-5050 4550) $PN AA68
J 0
(-5040 4560);
DISPLAY 0.489362 (-5040 4560);
PAINT MONO (-5040 4560);
FORCEPROP 0 LASTPIN (-5050 4500) $PN AA70
J 0
(-5040 4510);
DISPLAY 0.489362 (-5040 4510);
PAINT MONO (-5040 4510);
FORCEPROP 0 LASTPIN (-5050 4450) $PN AA75
J 0
(-5040 4460);
DISPLAY 0.489362 (-5040 4460);
PAINT MONO (-5040 4460);
FORCEPROP 0 LASTPIN (-5050 4400) $PN AB3
J 0
(-5040 4410);
DISPLAY 0.489362 (-5040 4410);
PAINT MONO (-5040 4410);
FORCEPROP 0 LASTPIN (-5050 4350) $PN AB5
J 0
(-5040 4360);
DISPLAY 0.489362 (-5040 4360);
PAINT MONO (-5040 4360);
FORCEPROP 0 LASTPIN (-5050 4300) $PN AB8
J 0
(-5040 4310);
DISPLAY 0.489362 (-5040 4310);
PAINT MONO (-5040 4310);
FORCEPROP 0 LASTPIN (-5050 4250) $PN AB10
J 0
(-5040 4260);
DISPLAY 0.489362 (-5040 4260);
PAINT MONO (-5040 4260);
FORCEPROP 0 LASTPIN (-5050 4200) $PN AB12
J 0
(-5040 4210);
DISPLAY 0.489362 (-5040 4210);
PAINT MONO (-5040 4210);
FORCEPROP 0 LASTPIN (-5050 4150) $PN AB15
J 0
(-5040 4160);
DISPLAY 0.489362 (-5040 4160);
PAINT MONO (-5040 4160);
FORCEPROP 0 LASTPIN (-5050 4100) $PN AB17
J 0
(-5040 4110);
DISPLAY 0.489362 (-5040 4110);
PAINT MONO (-5040 4110);
FORCEPROP 0 LASTPIN (-5050 4050) $PN AB19
J 0
(-5040 4060);
DISPLAY 0.489362 (-5040 4060);
PAINT MONO (-5040 4060);
FORCEPROP 0 LASTPIN (-5050 4000) $PN AB22
J 0
(-5040 4010);
DISPLAY 0.489362 (-5040 4010);
PAINT MONO (-5040 4010);
FORCEPROP 0 LASTPIN (-5050 3950) $PN AB25
J 0
(-5040 3960);
DISPLAY 0.489362 (-5040 3960);
PAINT MONO (-5040 3960);
FORCEPROP 0 LASTPIN (-5050 3900) $PN AB28
J 0
(-5040 3910);
DISPLAY 0.489362 (-5040 3910);
PAINT MONO (-5040 3910);
FORCEPROP 0 LASTPIN (-5050 3850) $PN AB31
J 0
(-5040 3860);
DISPLAY 0.489362 (-5040 3860);
PAINT MONO (-5040 3860);
FORCEPROP 0 LASTPIN (-5050 3800) $PN AB34
J 0
(-5040 3810);
DISPLAY 0.489362 (-5040 3810);
PAINT MONO (-5040 3810);
FORCEPROP 0 LASTPIN (-5050 3750) $PN AB37
J 0
(-5040 3760);
DISPLAY 0.489362 (-5040 3760);
PAINT MONO (-5040 3760);
FORCEPROP 0 LASTPIN (-5050 3700) $PN AB39
J 0
(-5040 3710);
DISPLAY 0.489362 (-5040 3710);
PAINT MONO (-5040 3710);
FORCEPROP 0 LASTPIN (-5050 3650) $PN AB42
J 0
(-5040 3660);
DISPLAY 0.489362 (-5040 3660);
PAINT MONO (-5040 3660);
FORCEPROP 0 LASTPIN (-5050 3600) $PN AB45
J 0
(-5040 3610);
DISPLAY 0.489362 (-5040 3610);
PAINT MONO (-5040 3610);
FORCEPROP 0 LASTPIN (-5050 3550) $PN AB48
J 0
(-5040 3560);
DISPLAY 0.489362 (-5040 3560);
PAINT MONO (-5040 3560);
FORCEPROP 0 LASTPIN (-5050 3500) $PN AB51
J 0
(-5040 3510);
DISPLAY 0.489362 (-5040 3510);
PAINT MONO (-5040 3510);
FORCEPROP 0 LASTPIN (-5050 3450) $PN AB54
J 0
(-5040 3460);
DISPLAY 0.489362 (-5040 3460);
PAINT MONO (-5040 3460);
FORCEPROP 0 LASTPIN (-5050 3400) $PN AB57
J 0
(-5040 3410);
DISPLAY 0.489362 (-5040 3410);
PAINT MONO (-5040 3410);
FORCEPROP 0 LASTPIN (-5050 3350) $PN AB59
J 0
(-5040 3360);
DISPLAY 0.489362 (-5040 3360);
PAINT MONO (-5040 3360);
FORCEPROP 0 LASTPIN (-5050 3300) $PN AB61
J 0
(-5040 3310);
DISPLAY 0.489362 (-5040 3310);
PAINT MONO (-5040 3310);
FORCEPROP 0 LASTPIN (-5050 3250) $PN AB64
J 0
(-5040 3260);
DISPLAY 0.489362 (-5040 3260);
PAINT MONO (-5040 3260);
FORCEPROP 0 LASTPIN (-5050 3200) $PN AB66
J 0
(-5040 3210);
DISPLAY 0.489362 (-5040 3210);
PAINT MONO (-5040 3210);
FORCEPROP 0 LASTPIN (-5050 3150) $PN AB68
J 0
(-5040 3160);
DISPLAY 0.489362 (-5040 3160);
PAINT MONO (-5040 3160);
FORCEPROP 0 LASTPIN (-5050 3100) $PN AB71
J 0
(-5040 3110);
DISPLAY 0.489362 (-5040 3110);
PAINT MONO (-5040 3110);
FORCEPROP 0 LASTPIN (-5050 3050) $PN AB73
J 0
(-5040 3060);
DISPLAY 0.489362 (-5040 3060);
PAINT MONO (-5040 3060);
FORCEPROP 0 LASTPIN (-5050 3000) $PN AC1
J 0
(-5040 3010);
DISPLAY 0.489362 (-5040 3010);
PAINT MONO (-5040 3010);
FORCEPROP 0 LASTPIN (-5050 2950) $PN AC6
J 0
(-5040 2960);
DISPLAY 0.489362 (-5040 2960);
PAINT MONO (-5040 2960);
FORCEPROP 0 LASTPIN (-5050 2900) $PN AC8
J 0
(-5040 2910);
DISPLAY 0.489362 (-5040 2910);
PAINT MONO (-5040 2910);
FORCEPROP 0 LASTPIN (-5050 2850) $PN AC13
J 0
(-5040 2860);
DISPLAY 0.489362 (-5040 2860);
PAINT MONO (-5040 2860);
FORCEPROP 0 LASTPIN (-5050 2800) $PN AC15
J 0
(-5040 2810);
DISPLAY 0.489362 (-5040 2810);
PAINT MONO (-5040 2810);
FORCEPROP 0 LASTPIN (-5050 2750) $PN AC20
J 0
(-5040 2760);
DISPLAY 0.489362 (-5040 2760);
PAINT MONO (-5040 2760);
FORCEPROP 0 LASTPIN (-5050 2700) $PN AC22
J 0
(-5040 2710);
DISPLAY 0.489362 (-5040 2710);
PAINT MONO (-5040 2710);
FORCEPROP 0 LASTPIN (-5050 2650) $PN AC25
J 0
(-5040 2660);
DISPLAY 0.489362 (-5040 2660);
PAINT MONO (-5040 2660);
FORCEPROP 0 LASTPIN (-5050 2600) $PN AC28
J 0
(-5040 2610);
DISPLAY 0.489362 (-5040 2610);
PAINT MONO (-5040 2610);
FORCEPROP 0 LASTPIN (-5050 2550) $PN AC31
J 0
(-5040 2560);
DISPLAY 0.489362 (-5040 2560);
PAINT MONO (-5040 2560);
FORCEPROP 0 LASTPIN (-5050 2500) $PN AC34
J 0
(-5040 2510);
DISPLAY 0.489362 (-5040 2510);
PAINT MONO (-5040 2510);
FORCEPROP 0 LASTPIN (-5050 2450) $PN AC42
J 0
(-5040 2460);
DISPLAY 0.489362 (-5040 2460);
PAINT MONO (-5040 2460);
FORCEPROP 0 LASTPIN (-5050 2400) $PN AC45
J 0
(-5040 2410);
DISPLAY 0.489362 (-5040 2410);
PAINT MONO (-5040 2410);
FORCEPROP 0 LASTPIN (-5050 2350) $PN AC48
J 0
(-5040 2360);
DISPLAY 0.489362 (-5040 2360);
PAINT MONO (-5040 2360);
FORCEPROP 0 LASTPIN (-5050 2300) $PN AC51
J 0
(-5040 2310);
DISPLAY 0.489362 (-5040 2310);
PAINT MONO (-5040 2310);
FORCEPROP 0 LASTPIN (-5050 2250) $PN AC54
J 0
(-5040 2260);
DISPLAY 0.489362 (-5040 2260);
PAINT MONO (-5040 2260);
FORCEPROP 0 LASTPIN (-5050 2200) $PN AC56
J 0
(-5040 2210);
DISPLAY 0.489362 (-5040 2210);
PAINT MONO (-5040 2210);
FORCEPROP 0 LASTPIN (-5050 2150) $PN AC61
J 0
(-5040 2160);
DISPLAY 0.489362 (-5040 2160);
PAINT MONO (-5040 2160);
FORCEPROP 0 LASTPIN (-5050 2100) $PN AC63
J 0
(-5040 2110);
DISPLAY 0.489362 (-5040 2110);
PAINT MONO (-5040 2110);
FORCEPROP 0 LASTPIN (-5050 2050) $PN AC68
J 0
(-5040 2060);
DISPLAY 0.489362 (-5040 2060);
PAINT MONO (-5040 2060);
FORCEPROP 0 LASTPIN (-5050 2000) $PN AC70
J 0
(-5040 2010);
DISPLAY 0.489362 (-5040 2010);
PAINT MONO (-5040 2010);
FORCEPROP 0 LASTPIN (-5050 1950) $PN AC75
J 0
(-5040 1960);
DISPLAY 0.489362 (-5040 1960);
PAINT MONO (-5040 1960);
FORCEPROP 0 LASTPIN (-5050 1900) $PN AD3
J 0
(-5040 1910);
DISPLAY 0.489362 (-5040 1910);
PAINT MONO (-5040 1910);
FORCEPROP 0 LASTPIN (-5050 1850) $PN AD5
J 0
(-5040 1860);
DISPLAY 0.489362 (-5040 1860);
PAINT MONO (-5040 1860);
FORCEPROP 0 LASTPIN (-5050 1800) $PN AD8
J 0
(-5040 1810);
DISPLAY 0.489362 (-5040 1810);
PAINT MONO (-5040 1810);
FORCEPROP 0 LASTPIN (-5050 1750) $PN AD10
J 0
(-5040 1760);
DISPLAY 0.489362 (-5040 1760);
PAINT MONO (-5040 1760);
FORCEPROP 0 LASTPIN (-5050 1700) $PN AD12
J 0
(-5040 1710);
DISPLAY 0.489362 (-5040 1710);
PAINT MONO (-5040 1710);
FORCEPROP 0 LASTPIN (-5050 1650) $PN AD15
J 0
(-5040 1660);
DISPLAY 0.489362 (-5040 1660);
PAINT MONO (-5040 1660);
FORCEPROP 0 LASTPIN (-5050 1600) $PN AD17
J 0
(-5040 1610);
DISPLAY 0.489362 (-5040 1610);
PAINT MONO (-5040 1610);
FORCEPROP 0 LASTPIN (-5050 1550) $PN AD19
J 0
(-5040 1560);
DISPLAY 0.489362 (-5040 1560);
PAINT MONO (-5040 1560);
FORCEPROP 0 LASTPIN (-5050 1500) $PN AD23
J 0
(-5040 1510);
DISPLAY 0.489362 (-5040 1510);
PAINT MONO (-5040 1510);
FORCEPROP 0 LASTPIN (-5050 1450) $PN AD24
J 0
(-5040 1460);
DISPLAY 0.489362 (-5040 1460);
PAINT MONO (-5040 1460);
FORCEPROP 0 LASTPIN (-5050 1400) $PN AD25
J 0
(-5040 1410);
DISPLAY 0.489362 (-5040 1410);
PAINT MONO (-5040 1410);
FORCEPROP 0 LASTPIN (-5050 1350) $PN AD26
J 0
(-5040 1360);
DISPLAY 0.489362 (-5040 1360);
PAINT MONO (-5040 1360);
FORCEPROP 0 LASTPIN (-5050 1300) $PN AD27
J 0
(-5040 1310);
DISPLAY 0.489362 (-5040 1310);
PAINT MONO (-5040 1310);
FORCEPROP 0 LASTPIN (-5050 1250) $PN AD28
J 0
(-5040 1260);
DISPLAY 0.489362 (-5040 1260);
PAINT MONO (-5040 1260);
FORCEPROP 0 LASTPIN (-5050 1200) $PN AD29
J 0
(-5040 1210);
DISPLAY 0.489362 (-5040 1210);
PAINT MONO (-5040 1210);
FORCEPROP 0 LASTPIN (-5050 1150) $PN AD30
J 0
(-5040 1160);
DISPLAY 0.489362 (-5040 1160);
PAINT MONO (-5040 1160);
FORCEPROP 0 LASTPIN (-5050 1100) $PN AD32
J 0
(-5040 1110);
DISPLAY 0.489362 (-5040 1110);
PAINT MONO (-5040 1110);
FORCEPROP 0 LASTPIN (-5050 1050) $PN AD33
J 0
(-5040 1060);
DISPLAY 0.489362 (-5040 1060);
PAINT MONO (-5040 1060);
FORCEPROP 0 LASTPIN (-5050 1000) $PN AD34
J 0
(-5040 1010);
DISPLAY 0.489362 (-5040 1010);
PAINT MONO (-5040 1010);
FORCEPROP 0 LASTPIN (-5050 950) $PN AD37
J 0
(-5040 960);
DISPLAY 0.489362 (-5040 960);
PAINT MONO (-5040 960);
FORCEPROP 0 LASTPIN (-5050 900) $PN AD39
J 0
(-5040 910);
DISPLAY 0.489362 (-5040 910);
PAINT MONO (-5040 910);
FORCEPROP 0 LASTPIN (-5050 850) $PN AD42
J 0
(-5040 860);
DISPLAY 0.489362 (-5040 860);
PAINT MONO (-5040 860);
FORCEPROP 0 LASTPIN (-5050 800) $PN AD43
J 0
(-5040 810);
DISPLAY 0.489362 (-5040 810);
PAINT MONO (-5040 810);
FORCEPROP 0 LASTPIN (-5050 750) $PN AD44
J 0
(-5040 760);
DISPLAY 0.489362 (-5040 760);
PAINT MONO (-5040 760);
FORCEPROP 0 LASTPIN (-5050 700) $PN AD45
J 0
(-5040 710);
DISPLAY 0.489362 (-5040 710);
PAINT MONO (-5040 710);
FORCEPROP 0 LASTPIN (-5050 650) $PN AD46
J 0
(-5040 660);
DISPLAY 0.489362 (-5040 660);
PAINT MONO (-5040 660);
FORCEPROP 0 LASTPIN (-5050 600) $PN AD47
J 0
(-5040 610);
DISPLAY 0.489362 (-5040 610);
PAINT MONO (-5040 610);
FORCEPROP 0 LASTPIN (-5050 550) $PN AD48
J 0
(-5040 560);
DISPLAY 0.489362 (-5040 560);
PAINT MONO (-5040 560);
FORCEPROP 0 LASTPIN (-6150 6300) $PN T66
J 2
(-6160 6310);
DISPLAY 0.489362 (-6160 6310);
PAINT MONO (-6160 6310);
FORCEPROP 0 LASTPIN (-6150 6250) $PN T68
J 2
(-6160 6260);
DISPLAY 0.489362 (-6160 6260);
PAINT MONO (-6160 6260);
FORCEPROP 0 LASTPIN (-6150 6200) $PN T71
J 2
(-6160 6210);
DISPLAY 0.489362 (-6160 6210);
PAINT MONO (-6160 6210);
FORCEPROP 0 LASTPIN (-6150 6150) $PN T73
J 2
(-6160 6160);
DISPLAY 0.489362 (-6160 6160);
PAINT MONO (-6160 6160);
FORCEPROP 0 LASTPIN (-6150 6100) $PN U1
J 2
(-6160 6110);
DISPLAY 0.489362 (-6160 6110);
PAINT MONO (-6160 6110);
FORCEPROP 0 LASTPIN (-6150 6050) $PN U6
J 2
(-6160 6060);
DISPLAY 0.489362 (-6160 6060);
PAINT MONO (-6160 6060);
FORCEPROP 0 LASTPIN (-6150 6000) $PN U8
J 2
(-6160 6010);
DISPLAY 0.489362 (-6160 6010);
PAINT MONO (-6160 6010);
FORCEPROP 0 LASTPIN (-6150 5950) $PN U13
J 2
(-6160 5960);
DISPLAY 0.489362 (-6160 5960);
PAINT MONO (-6160 5960);
FORCEPROP 0 LASTPIN (-6150 5900) $PN U15
J 2
(-6160 5910);
DISPLAY 0.489362 (-6160 5910);
PAINT MONO (-6160 5910);
FORCEPROP 0 LASTPIN (-6150 5850) $PN U20
J 2
(-6160 5860);
DISPLAY 0.489362 (-6160 5860);
PAINT MONO (-6160 5860);
FORCEPROP 0 LASTPIN (-6150 5800) $PN U22
J 2
(-6160 5810);
DISPLAY 0.489362 (-6160 5810);
PAINT MONO (-6160 5810);
FORCEPROP 0 LASTPIN (-6150 5750) $PN U25
J 2
(-6160 5760);
DISPLAY 0.489362 (-6160 5760);
PAINT MONO (-6160 5760);
FORCEPROP 0 LASTPIN (-6150 5700) $PN U28
J 2
(-6160 5710);
DISPLAY 0.489362 (-6160 5710);
PAINT MONO (-6160 5710);
FORCEPROP 0 LASTPIN (-6150 5650) $PN U31
J 2
(-6160 5660);
DISPLAY 0.489362 (-6160 5660);
PAINT MONO (-6160 5660);
FORCEPROP 0 LASTPIN (-6150 5600) $PN U34
J 2
(-6160 5610);
DISPLAY 0.489362 (-6160 5610);
PAINT MONO (-6160 5610);
FORCEPROP 0 LASTPIN (-6150 5550) $PN U42
J 2
(-6160 5560);
DISPLAY 0.489362 (-6160 5560);
PAINT MONO (-6160 5560);
FORCEPROP 0 LASTPIN (-6150 5500) $PN U45
J 2
(-6160 5510);
DISPLAY 0.489362 (-6160 5510);
PAINT MONO (-6160 5510);
FORCEPROP 0 LASTPIN (-6150 5450) $PN U48
J 2
(-6160 5460);
DISPLAY 0.489362 (-6160 5460);
PAINT MONO (-6160 5460);
FORCEPROP 0 LASTPIN (-6150 5400) $PN U51
J 2
(-6160 5410);
DISPLAY 0.489362 (-6160 5410);
PAINT MONO (-6160 5410);
FORCEPROP 0 LASTPIN (-6150 5350) $PN U54
J 2
(-6160 5360);
DISPLAY 0.489362 (-6160 5360);
PAINT MONO (-6160 5360);
FORCEPROP 0 LASTPIN (-6150 5300) $PN U56
J 2
(-6160 5310);
DISPLAY 0.489362 (-6160 5310);
PAINT MONO (-6160 5310);
FORCEPROP 0 LASTPIN (-6150 5250) $PN U61
J 2
(-6160 5260);
DISPLAY 0.489362 (-6160 5260);
PAINT MONO (-6160 5260);
FORCEPROP 0 LASTPIN (-6150 5200) $PN U63
J 2
(-6160 5210);
DISPLAY 0.489362 (-6160 5210);
PAINT MONO (-6160 5210);
FORCEPROP 0 LASTPIN (-6150 5150) $PN U68
J 2
(-6160 5160);
DISPLAY 0.489362 (-6160 5160);
PAINT MONO (-6160 5160);
FORCEPROP 0 LASTPIN (-6150 5100) $PN U70
J 2
(-6160 5110);
DISPLAY 0.489362 (-6160 5110);
PAINT MONO (-6160 5110);
FORCEPROP 0 LASTPIN (-6150 5050) $PN U75
J 2
(-6160 5060);
DISPLAY 0.489362 (-6160 5060);
PAINT MONO (-6160 5060);
FORCEPROP 0 LASTPIN (-6150 5000) $PN V3
J 2
(-6160 5010);
DISPLAY 0.489362 (-6160 5010);
PAINT MONO (-6160 5010);
FORCEPROP 0 LASTPIN (-6150 4950) $PN V5
J 2
(-6160 4960);
DISPLAY 0.489362 (-6160 4960);
PAINT MONO (-6160 4960);
FORCEPROP 0 LASTPIN (-6150 4900) $PN V8
J 2
(-6160 4910);
DISPLAY 0.489362 (-6160 4910);
PAINT MONO (-6160 4910);
FORCEPROP 0 LASTPIN (-6150 4850) $PN V10
J 2
(-6160 4860);
DISPLAY 0.489362 (-6160 4860);
PAINT MONO (-6160 4860);
FORCEPROP 0 LASTPIN (-6150 4800) $PN V12
J 2
(-6160 4810);
DISPLAY 0.489362 (-6160 4810);
PAINT MONO (-6160 4810);
FORCEPROP 0 LASTPIN (-6150 4750) $PN V15
J 2
(-6160 4760);
DISPLAY 0.489362 (-6160 4760);
PAINT MONO (-6160 4760);
FORCEPROP 0 LASTPIN (-6150 4700) $PN V17
J 2
(-6160 4710);
DISPLAY 0.489362 (-6160 4710);
PAINT MONO (-6160 4710);
FORCEPROP 0 LASTPIN (-6150 4650) $PN V19
J 2
(-6160 4660);
DISPLAY 0.489362 (-6160 4660);
PAINT MONO (-6160 4660);
FORCEPROP 0 LASTPIN (-6150 4600) $PN V23
J 2
(-6160 4610);
DISPLAY 0.489362 (-6160 4610);
PAINT MONO (-6160 4610);
FORCEPROP 0 LASTPIN (-6150 4550) $PN V24
J 2
(-6160 4560);
DISPLAY 0.489362 (-6160 4560);
PAINT MONO (-6160 4560);
FORCEPROP 0 LASTPIN (-6150 4500) $PN V25
J 2
(-6160 4510);
DISPLAY 0.489362 (-6160 4510);
PAINT MONO (-6160 4510);
FORCEPROP 0 LASTPIN (-6150 4450) $PN V26
J 2
(-6160 4460);
DISPLAY 0.489362 (-6160 4460);
PAINT MONO (-6160 4460);
FORCEPROP 0 LASTPIN (-6150 4400) $PN V28
J 2
(-6160 4410);
DISPLAY 0.489362 (-6160 4410);
PAINT MONO (-6160 4410);
FORCEPROP 0 LASTPIN (-6150 4350) $PN V29
J 2
(-6160 4360);
DISPLAY 0.489362 (-6160 4360);
PAINT MONO (-6160 4360);
FORCEPROP 0 LASTPIN (-6150 4300) $PN V30
J 2
(-6160 4310);
DISPLAY 0.489362 (-6160 4310);
PAINT MONO (-6160 4310);
FORCEPROP 0 LASTPIN (-6150 4250) $PN V31
J 2
(-6160 4260);
DISPLAY 0.489362 (-6160 4260);
PAINT MONO (-6160 4260);
FORCEPROP 0 LASTPIN (-6150 4200) $PN V32
J 2
(-6160 4210);
DISPLAY 0.489362 (-6160 4210);
PAINT MONO (-6160 4210);
FORCEPROP 0 LASTPIN (-6150 4150) $PN V33
J 2
(-6160 4160);
DISPLAY 0.489362 (-6160 4160);
PAINT MONO (-6160 4160);
FORCEPROP 0 LASTPIN (-6150 4100) $PN V34
J 2
(-6160 4110);
DISPLAY 0.489362 (-6160 4110);
PAINT MONO (-6160 4110);
FORCEPROP 0 LASTPIN (-6150 4050) $PN V37
J 2
(-6160 4060);
DISPLAY 0.489362 (-6160 4060);
PAINT MONO (-6160 4060);
FORCEPROP 0 LASTPIN (-6150 4000) $PN V39
J 2
(-6160 4010);
DISPLAY 0.489362 (-6160 4010);
PAINT MONO (-6160 4010);
FORCEPROP 0 LASTPIN (-6150 3950) $PN V42
J 2
(-6160 3960);
DISPLAY 0.489362 (-6160 3960);
PAINT MONO (-6160 3960);
FORCEPROP 0 LASTPIN (-6150 3900) $PN V43
J 2
(-6160 3910);
DISPLAY 0.489362 (-6160 3910);
PAINT MONO (-6160 3910);
FORCEPROP 0 LASTPIN (-6150 3850) $PN V44
J 2
(-6160 3860);
DISPLAY 0.489362 (-6160 3860);
PAINT MONO (-6160 3860);
FORCEPROP 0 LASTPIN (-6150 3800) $PN V45
J 2
(-6160 3810);
DISPLAY 0.489362 (-6160 3810);
PAINT MONO (-6160 3810);
FORCEPROP 0 LASTPIN (-6150 3750) $PN V46
J 2
(-6160 3760);
DISPLAY 0.489362 (-6160 3760);
PAINT MONO (-6160 3760);
FORCEPROP 0 LASTPIN (-6150 3700) $PN V47
J 2
(-6160 3710);
DISPLAY 0.489362 (-6160 3710);
PAINT MONO (-6160 3710);
FORCEPROP 0 LASTPIN (-6150 3650) $PN V48
J 2
(-6160 3660);
DISPLAY 0.489362 (-6160 3660);
PAINT MONO (-6160 3660);
FORCEPROP 0 LASTPIN (-6150 3600) $PN V49
J 2
(-6160 3610);
DISPLAY 0.489362 (-6160 3610);
PAINT MONO (-6160 3610);
FORCEPROP 0 LASTPIN (-6150 3550) $PN V50
J 2
(-6160 3560);
DISPLAY 0.489362 (-6160 3560);
PAINT MONO (-6160 3560);
FORCEPROP 0 LASTPIN (-6150 3500) $PN V51
J 2
(-6160 3510);
DISPLAY 0.489362 (-6160 3510);
PAINT MONO (-6160 3510);
FORCEPROP 0 LASTPIN (-6150 3450) $PN V52
J 2
(-6160 3460);
DISPLAY 0.489362 (-6160 3460);
PAINT MONO (-6160 3460);
FORCEPROP 0 LASTPIN (-6150 3400) $PN V53
J 2
(-6160 3410);
DISPLAY 0.489362 (-6160 3410);
PAINT MONO (-6160 3410);
FORCEPROP 0 LASTPIN (-6150 3350) $PN V57
J 2
(-6160 3360);
DISPLAY 0.489362 (-6160 3360);
PAINT MONO (-6160 3360);
FORCEPROP 0 LASTPIN (-6150 3300) $PN V59
J 2
(-6160 3310);
DISPLAY 0.489362 (-6160 3310);
PAINT MONO (-6160 3310);
FORCEPROP 0 LASTPIN (-6150 3250) $PN V61
J 2
(-6160 3260);
DISPLAY 0.489362 (-6160 3260);
PAINT MONO (-6160 3260);
FORCEPROP 0 LASTPIN (-6150 3200) $PN V64
J 2
(-6160 3210);
DISPLAY 0.489362 (-6160 3210);
PAINT MONO (-6160 3210);
FORCEPROP 0 LASTPIN (-6150 3150) $PN V66
J 2
(-6160 3160);
DISPLAY 0.489362 (-6160 3160);
PAINT MONO (-6160 3160);
FORCEPROP 0 LASTPIN (-6150 3100) $PN V71
J 2
(-6160 3110);
DISPLAY 0.489362 (-6160 3110);
PAINT MONO (-6160 3110);
FORCEPROP 0 LASTPIN (-6150 3050) $PN V73
J 2
(-6160 3060);
DISPLAY 0.489362 (-6160 3060);
PAINT MONO (-6160 3060);
FORCEPROP 0 LASTPIN (-6150 3000) $PN W1
J 2
(-6160 3010);
DISPLAY 0.489362 (-6160 3010);
PAINT MONO (-6160 3010);
FORCEPROP 0 LASTPIN (-6150 2950) $PN W4
J 2
(-6160 2960);
DISPLAY 0.489362 (-6160 2960);
PAINT MONO (-6160 2960);
FORCEPROP 0 LASTPIN (-6150 2900) $PN W6
J 2
(-6160 2910);
DISPLAY 0.489362 (-6160 2910);
PAINT MONO (-6160 2910);
FORCEPROP 0 LASTPIN (-6150 2850) $PN W8
J 2
(-6160 2860);
DISPLAY 0.489362 (-6160 2860);
PAINT MONO (-6160 2860);
FORCEPROP 0 LASTPIN (-6150 2800) $PN W11
J 2
(-6160 2810);
DISPLAY 0.489362 (-6160 2810);
PAINT MONO (-6160 2810);
FORCEPROP 0 LASTPIN (-6150 2750) $PN W13
J 2
(-6160 2760);
DISPLAY 0.489362 (-6160 2760);
PAINT MONO (-6160 2760);
FORCEPROP 0 LASTPIN (-6150 2700) $PN W15
J 2
(-6160 2710);
DISPLAY 0.489362 (-6160 2710);
PAINT MONO (-6160 2710);
FORCEPROP 0 LASTPIN (-6150 2650) $PN W18
J 2
(-6160 2660);
DISPLAY 0.489362 (-6160 2660);
PAINT MONO (-6160 2660);
FORCEPROP 0 LASTPIN (-6150 2600) $PN W20
J 2
(-6160 2610);
DISPLAY 0.489362 (-6160 2610);
PAINT MONO (-6160 2610);
FORCEPROP 0 LASTPIN (-6150 2550) $PN W22
J 2
(-6160 2560);
DISPLAY 0.489362 (-6160 2560);
PAINT MONO (-6160 2560);
FORCEPROP 0 LASTPIN (-6150 2500) $PN W25
J 2
(-6160 2510);
DISPLAY 0.489362 (-6160 2510);
PAINT MONO (-6160 2510);
FORCEPROP 0 LASTPIN (-6150 2450) $PN W28
J 2
(-6160 2460);
DISPLAY 0.489362 (-6160 2460);
PAINT MONO (-6160 2460);
FORCEPROP 0 LASTPIN (-6150 2400) $PN W34
J 2
(-6160 2410);
DISPLAY 0.489362 (-6160 2410);
PAINT MONO (-6160 2410);
FORCEPROP 0 LASTPIN (-6150 2350) $PN W35
J 2
(-6160 2360);
DISPLAY 0.489362 (-6160 2360);
PAINT MONO (-6160 2360);
FORCEPROP 0 LASTPIN (-6150 2300) $PN W36
J 2
(-6160 2310);
DISPLAY 0.489362 (-6160 2310);
PAINT MONO (-6160 2310);
FORCEPROP 0 LASTPIN (-6150 2250) $PN W40
J 2
(-6160 2260);
DISPLAY 0.489362 (-6160 2260);
PAINT MONO (-6160 2260);
FORCEPROP 0 LASTPIN (-6150 2200) $PN W41
J 2
(-6160 2210);
DISPLAY 0.489362 (-6160 2210);
PAINT MONO (-6160 2210);
FORCEPROP 0 LASTPIN (-6150 2150) $PN W42
J 2
(-6160 2160);
DISPLAY 0.489362 (-6160 2160);
PAINT MONO (-6160 2160);
FORCEPROP 0 LASTPIN (-6150 2100) $PN W45
J 2
(-6160 2110);
DISPLAY 0.489362 (-6160 2110);
PAINT MONO (-6160 2110);
FORCEPROP 0 LASTPIN (-6150 2050) $PN W48
J 2
(-6160 2060);
DISPLAY 0.489362 (-6160 2060);
PAINT MONO (-6160 2060);
FORCEPROP 0 LASTPIN (-6150 2000) $PN W51
J 2
(-6160 2010);
DISPLAY 0.489362 (-6160 2010);
PAINT MONO (-6160 2010);
FORCEPROP 0 LASTPIN (-6150 1950) $PN W54
J 2
(-6160 1960);
DISPLAY 0.489362 (-6160 1960);
PAINT MONO (-6160 1960);
FORCEPROP 0 LASTPIN (-6150 1900) $PN W56
J 2
(-6160 1910);
DISPLAY 0.489362 (-6160 1910);
PAINT MONO (-6160 1910);
FORCEPROP 0 LASTPIN (-6150 1850) $PN W58
J 2
(-6160 1860);
DISPLAY 0.489362 (-6160 1860);
PAINT MONO (-6160 1860);
FORCEPROP 0 LASTPIN (-6150 1800) $PN W61
J 2
(-6160 1810);
DISPLAY 0.489362 (-6160 1810);
PAINT MONO (-6160 1810);
FORCEPROP 0 LASTPIN (-6150 1750) $PN W63
J 2
(-6160 1760);
DISPLAY 0.489362 (-6160 1760);
PAINT MONO (-6160 1760);
FORCEPROP 0 LASTPIN (-6150 1700) $PN W65
J 2
(-6160 1710);
DISPLAY 0.489362 (-6160 1710);
PAINT MONO (-6160 1710);
FORCEPROP 0 LASTPIN (-6150 1650) $PN W68
J 2
(-6160 1660);
DISPLAY 0.489362 (-6160 1660);
PAINT MONO (-6160 1660);
FORCEPROP 0 LASTPIN (-6150 1600) $PN W70
J 2
(-6160 1610);
DISPLAY 0.489362 (-6160 1610);
PAINT MONO (-6160 1610);
FORCEPROP 0 LASTPIN (-6150 1550) $PN W72
J 2
(-6160 1560);
DISPLAY 0.489362 (-6160 1560);
PAINT MONO (-6160 1560);
FORCEPROP 0 LASTPIN (-6150 1500) $PN W75
J 2
(-6160 1510);
DISPLAY 0.489362 (-6160 1510);
PAINT MONO (-6160 1510);
FORCEPROP 0 LASTPIN (-6150 1450) $PN Y3
J 2
(-6160 1460);
DISPLAY 0.489362 (-6160 1460);
PAINT MONO (-6160 1460);
FORCEPROP 0 LASTPIN (-6150 1400) $PN Y8
J 2
(-6160 1410);
DISPLAY 0.489362 (-6160 1410);
PAINT MONO (-6160 1410);
FORCEPROP 0 LASTPIN (-6150 1350) $PN Y10
J 2
(-6160 1360);
DISPLAY 0.489362 (-6160 1360);
PAINT MONO (-6160 1360);
FORCEPROP 0 LASTPIN (-6150 1300) $PN Y15
J 2
(-6160 1310);
DISPLAY 0.489362 (-6160 1310);
PAINT MONO (-6160 1310);
FORCEPROP 0 LASTPIN (-6150 1250) $PN Y17
J 2
(-6160 1260);
DISPLAY 0.489362 (-6160 1260);
PAINT MONO (-6160 1260);
FORCEPROP 0 LASTPIN (-6150 1200) $PN Y22
J 2
(-6160 1210);
DISPLAY 0.489362 (-6160 1210);
PAINT MONO (-6160 1210);
FORCEPROP 0 LASTPIN (-6150 1150) $PN Y23
J 2
(-6160 1160);
DISPLAY 0.489362 (-6160 1160);
PAINT MONO (-6160 1160);
FORCEPROP 0 LASTPIN (-6150 1100) $PN Y24
J 2
(-6160 1110);
DISPLAY 0.489362 (-6160 1110);
PAINT MONO (-6160 1110);
FORCEPROP 0 LASTPIN (-6150 1050) $PN Y25
J 2
(-6160 1060);
DISPLAY 0.489362 (-6160 1060);
PAINT MONO (-6160 1060);
FORCEPROP 0 LASTPIN (-6150 1000) $PN Y26
J 2
(-6160 1010);
DISPLAY 0.489362 (-6160 1010);
PAINT MONO (-6160 1010);
FORCEPROP 0 LASTPIN (-6150 950) $PN Y27
J 2
(-6160 960);
DISPLAY 0.489362 (-6160 960);
PAINT MONO (-6160 960);
FORCEPROP 0 LASTPIN (-6150 900) $PN Y28
J 2
(-6160 910);
DISPLAY 0.489362 (-6160 910);
PAINT MONO (-6160 910);
FORCEPROP 0 LASTPIN (-6150 850) $PN Y31
J 2
(-6160 860);
DISPLAY 0.489362 (-6160 860);
PAINT MONO (-6160 860);
FORCEPROP 0 LASTPIN (-6150 800) $PN Y32
J 2
(-6160 810);
DISPLAY 0.489362 (-6160 810);
PAINT MONO (-6160 810);
FORCEPROP 0 LASTPIN (-6150 750) $PN Y33
J 2
(-6160 760);
DISPLAY 0.489362 (-6160 760);
PAINT MONO (-6160 760);
FORCEPROP 0 LASTPIN (-6150 700) $PN Y34
J 2
(-6160 710);
DISPLAY 0.489362 (-6160 710);
PAINT MONO (-6160 710);
FORCEPROP 0 LASTPIN (-6150 650) $PN Y37
J 2
(-6160 660);
DISPLAY 0.489362 (-6160 660);
PAINT MONO (-6160 660);
FORCEPROP 0 LASTPIN (-6150 600) $PN Y39
J 2
(-6160 610);
DISPLAY 0.489362 (-6160 610);
PAINT MONO (-6160 610);
FORCEPROP 0 LASTPIN (-6150 550) $PN Y42
J 2
(-6160 560);
DISPLAY 0.489362 (-6160 560);
PAINT MONO (-6160 560);
FORCEPROP 0 LASTPIN (-6150 500) $PN Y43
J 2
(-6160 510);
DISPLAY 0.489362 (-6160 510);
PAINT MONO (-6160 510);
FORCEPROP 0 LASTPIN (-5050 6300) $PN Y44
J 0
(-5040 6310);
DISPLAY 0.489362 (-5040 6310);
PAINT MONO (-5040 6310);
FORCEPROP 0 LASTPIN (-5050 6250) $PN Y45
J 0
(-5040 6260);
DISPLAY 0.489362 (-5040 6260);
PAINT MONO (-5040 6260);
FORCEPROP 0 LASTPIN (-5050 6200) $PN Y48
J 0
(-5040 6210);
DISPLAY 0.489362 (-5040 6210);
PAINT MONO (-5040 6210);
FORCEPROP 0 LASTPIN (-5050 6150) $PN Y49
J 0
(-5040 6160);
DISPLAY 0.489362 (-5040 6160);
PAINT MONO (-5040 6160);
FORCEPROP 0 LASTPIN (-5050 6100) $PN Y50
J 0
(-5040 6110);
DISPLAY 0.489362 (-5040 6110);
PAINT MONO (-5040 6110);
FORCEPROP 0 LASTPIN (-5050 6050) $PN Y51
J 0
(-5040 6060);
DISPLAY 0.489362 (-5040 6060);
PAINT MONO (-5040 6060);
FORCEPROP 0 LASTPIN (-5050 6000) $PN Y52
J 0
(-5040 6010);
DISPLAY 0.489362 (-5040 6010);
PAINT MONO (-5040 6010);
FORCEPROP 0 LASTPIN (-5050 5950) $PN Y53
J 0
(-5040 5960);
DISPLAY 0.489362 (-5040 5960);
PAINT MONO (-5040 5960);
FORCEPROP 0 LASTPIN (-5050 5900) $PN Y54
J 0
(-5040 5910);
DISPLAY 0.489362 (-5040 5910);
PAINT MONO (-5040 5910);
FORCEPROP 0 LASTPIN (-5050 5850) $PN Y59
J 0
(-5040 5860);
DISPLAY 0.489362 (-5040 5860);
PAINT MONO (-5040 5860);
FORCEPROP 0 LASTPIN (-5050 5800) $PN Y61
J 0
(-5040 5810);
DISPLAY 0.489362 (-5040 5810);
PAINT MONO (-5040 5810);
FORCEPROP 0 LASTPIN (-5050 5750) $PN Y66
J 0
(-5040 5760);
DISPLAY 0.489362 (-5040 5760);
PAINT MONO (-5040 5760);
FORCEPROP 0 LASTPIN (-5050 5700) $PN Y68
J 0
(-5040 5710);
DISPLAY 0.489362 (-5040 5710);
PAINT MONO (-5040 5710);
FORCEPROP 0 LASTPIN (-5050 5650) $PN Y73
J 0
(-5040 5660);
DISPLAY 0.489362 (-5040 5660);
PAINT MONO (-5040 5660);
FORCEPROP 2 LAST PART_TYPE SMLF
J 0
(-6000 6700);
DISPLAY 1.021277 (-6000 6700);
FORCEPROP 1 LAST MATERIAL IO
J 0
(-5995 6532);
DISPLAY 0.489362 (-5995 6532);
PAINT SKYBLUE (-5995 6532);
FORCEPROP 2 LAST VALUE SOCKET6096_13568-001
J 0
(-6000 6575);
DISPLAY 0.489362 (-6000 6575);
PAINT SKYBLUE (-6000 6575);
FORCEPROP 1 LAST NEEDS_NO_SIZE TRUE
J 0
(-5600 3450);
DISPLAY 0.723404 (-5600 3450);
PAINT GREEN (-5600 3450);
DISPLAY INVISIBLE (-5600 3450);
FORCEPROP 1 LAST CDS_LMAN_SYM_OUTLINE -400,3050,400,-3050
J 0
(-5600 3450);
DISPLAY 0.468085 (-5600 3450);
PAINT GREEN (-5600 3450);
DISPLAY INVISIBLE (-5600 3450);
FORCEPROP 2 LAST CDS_LIB pure_quanta
J 0
(-5600 3450);
DISPLAY INVISIBLE (-5600 3450);
FORCEPROP 1 LAST PATH I21
J 0
(-5600 3450);
DISPLAY 0.723404 (-5600 3450);
PAINT GREEN (-5600 3450);
DISPLAY INVISIBLE (-5600 3450);
FORCEPROP 1 LAST PART_NUMBER DGA^6000030
J 0
(-5995 6650);
DISPLAY 0.489362 (-5995 6650);
PAINT SKYBLUE (-5995 6650);
DISPLAY INVISIBLE (-5995 6650);
FORCEADD GENOA_SP5..31
(-4100 3475);
FORCEPROP 1 LAST LOCATION U25
J 0
(-4495 6600);
DISPLAY 0.489362 (-4495 6600);
PAINT SKYBLUE (-4495 6600);
FORCEPROP 0 LAST $SEC 31
J 0
(-4475 6875);
DISPLAY 0.680851 (-4475 6875);
PAINT MONO (-4475 6875);
DISPLAY INVISIBLE (-4475 6875);
FORCEPROP 0 LAST CDS_SEC 31
J 0
(-4700 6725);
DISPLAY 1.021277 (-4700 6725);
DISPLAY INVISIBLE (-4700 6725);
FORCEPROP 0 LASTPIN (-4650 6375) $PN AD49
J 2
(-4635 6385);
DISPLAY 0.489362 (-4635 6385);
PAINT MONO (-4635 6385);
FORCEPROP 0 LASTPIN (-4650 6325) $PN AD50
J 2
(-4635 6335);
DISPLAY 0.489362 (-4635 6335);
PAINT MONO (-4635 6335);
FORCEPROP 0 LASTPIN (-4650 6275) $PN AD51
J 2
(-4635 6285);
DISPLAY 0.489362 (-4635 6285);
PAINT MONO (-4635 6285);
FORCEPROP 0 LASTPIN (-4650 6225) $PN AD52
J 2
(-4635 6235);
DISPLAY 0.489362 (-4635 6235);
PAINT MONO (-4635 6235);
FORCEPROP 0 LASTPIN (-4650 6175) $PN AD53
J 2
(-4635 6185);
DISPLAY 0.489362 (-4635 6185);
PAINT MONO (-4635 6185);
FORCEPROP 0 LASTPIN (-4650 6125) $PN AD57
J 2
(-4635 6135);
DISPLAY 0.489362 (-4635 6135);
PAINT MONO (-4635 6135);
FORCEPROP 0 LASTPIN (-4650 6075) $PN AD59
J 2
(-4635 6085);
DISPLAY 0.489362 (-4635 6085);
PAINT MONO (-4635 6085);
FORCEPROP 0 LASTPIN (-4650 6025) $PN AD61
J 2
(-4635 6035);
DISPLAY 0.489362 (-4635 6035);
PAINT MONO (-4635 6035);
FORCEPROP 0 LASTPIN (-4650 5975) $PN AD64
J 2
(-4635 5985);
DISPLAY 0.489362 (-4635 5985);
PAINT MONO (-4635 5985);
FORCEPROP 0 LASTPIN (-4650 5925) $PN AD66
J 2
(-4635 5935);
DISPLAY 0.489362 (-4635 5935);
PAINT MONO (-4635 5935);
FORCEPROP 0 LASTPIN (-4650 5875) $PN AD68
J 2
(-4635 5885);
DISPLAY 0.489362 (-4635 5885);
PAINT MONO (-4635 5885);
FORCEPROP 0 LASTPIN (-4650 5825) $PN AD71
J 2
(-4635 5835);
DISPLAY 0.489362 (-4635 5835);
PAINT MONO (-4635 5835);
FORCEPROP 0 LASTPIN (-4650 5775) $PN AD73
J 2
(-4635 5785);
DISPLAY 0.489362 (-4635 5785);
PAINT MONO (-4635 5785);
FORCEPROP 0 LASTPIN (-4650 5725) $PN AE1
J 2
(-4635 5735);
DISPLAY 0.489362 (-4635 5735);
PAINT MONO (-4635 5735);
FORCEPROP 0 LASTPIN (-4650 5675) $PN AE6
J 2
(-4635 5685);
DISPLAY 0.489362 (-4635 5685);
PAINT MONO (-4635 5685);
FORCEPROP 0 LASTPIN (-4650 5625) $PN AE8
J 2
(-4635 5635);
DISPLAY 0.489362 (-4635 5635);
PAINT MONO (-4635 5635);
FORCEPROP 0 LASTPIN (-4650 5575) $PN AE11
J 2
(-4635 5585);
DISPLAY 0.489362 (-4635 5585);
PAINT MONO (-4635 5585);
FORCEPROP 0 LASTPIN (-4650 5525) $PN AE13
J 2
(-4635 5535);
DISPLAY 0.489362 (-4635 5535);
PAINT MONO (-4635 5535);
FORCEPROP 0 LASTPIN (-4650 5475) $PN AE15
J 2
(-4635 5485);
DISPLAY 0.489362 (-4635 5485);
PAINT MONO (-4635 5485);
FORCEPROP 0 LASTPIN (-4650 5425) $PN AE18
J 2
(-4635 5435);
DISPLAY 0.489362 (-4635 5435);
PAINT MONO (-4635 5435);
FORCEPROP 0 LASTPIN (-4650 5375) $PN AE20
J 2
(-4635 5385);
DISPLAY 0.489362 (-4635 5385);
PAINT MONO (-4635 5385);
FORCEPROP 0 LASTPIN (-4650 5325) $PN AE22
J 2
(-4635 5335);
DISPLAY 0.489362 (-4635 5335);
PAINT MONO (-4635 5335);
FORCEPROP 0 LASTPIN (-4650 5275) $PN AE25
J 2
(-4635 5285);
DISPLAY 0.489362 (-4635 5285);
PAINT MONO (-4635 5285);
FORCEPROP 0 LASTPIN (-4650 5225) $PN AE28
J 2
(-4635 5235);
DISPLAY 0.489362 (-4635 5235);
PAINT MONO (-4635 5235);
FORCEPROP 0 LASTPIN (-4650 5175) $PN AE31
J 2
(-4635 5185);
DISPLAY 0.489362 (-4635 5185);
PAINT MONO (-4635 5185);
FORCEPROP 0 LASTPIN (-4650 5125) $PN AE34
J 2
(-4635 5135);
DISPLAY 0.489362 (-4635 5135);
PAINT MONO (-4635 5135);
FORCEPROP 0 LASTPIN (-4650 5075) $PN AE35
J 2
(-4635 5085);
DISPLAY 0.489362 (-4635 5085);
PAINT MONO (-4635 5085);
FORCEPROP 0 LASTPIN (-4650 5025) $PN AE36
J 2
(-4635 5035);
DISPLAY 0.489362 (-4635 5035);
PAINT MONO (-4635 5035);
FORCEPROP 0 LASTPIN (-4650 4975) $PN AE40
J 2
(-4635 4985);
DISPLAY 0.489362 (-4635 4985);
PAINT MONO (-4635 4985);
FORCEPROP 0 LASTPIN (-4650 4925) $PN AE41
J 2
(-4635 4935);
DISPLAY 0.489362 (-4635 4935);
PAINT MONO (-4635 4935);
FORCEPROP 0 LASTPIN (-4650 4875) $PN AE42
J 2
(-4635 4885);
DISPLAY 0.489362 (-4635 4885);
PAINT MONO (-4635 4885);
FORCEPROP 0 LASTPIN (-4650 4825) $PN AE45
J 2
(-4635 4835);
DISPLAY 0.489362 (-4635 4835);
PAINT MONO (-4635 4835);
FORCEPROP 0 LASTPIN (-4650 4775) $PN AE48
J 2
(-4635 4785);
DISPLAY 0.489362 (-4635 4785);
PAINT MONO (-4635 4785);
FORCEPROP 0 LASTPIN (-4650 4725) $PN AE51
J 2
(-4635 4735);
DISPLAY 0.489362 (-4635 4735);
PAINT MONO (-4635 4735);
FORCEPROP 0 LASTPIN (-4650 4675) $PN AE54
J 2
(-4635 4685);
DISPLAY 0.489362 (-4635 4685);
PAINT MONO (-4635 4685);
FORCEPROP 0 LASTPIN (-4650 4625) $PN AE56
J 2
(-4635 4635);
DISPLAY 0.489362 (-4635 4635);
PAINT MONO (-4635 4635);
FORCEPROP 0 LASTPIN (-4650 4575) $PN AE58
J 2
(-4635 4585);
DISPLAY 0.489362 (-4635 4585);
PAINT MONO (-4635 4585);
FORCEPROP 0 LASTPIN (-4650 4525) $PN AE61
J 2
(-4635 4535);
DISPLAY 0.489362 (-4635 4535);
PAINT MONO (-4635 4535);
FORCEPROP 0 LASTPIN (-4650 4475) $PN AE63
J 2
(-4635 4485);
DISPLAY 0.489362 (-4635 4485);
PAINT MONO (-4635 4485);
FORCEPROP 0 LASTPIN (-4650 4425) $PN AE65
J 2
(-4635 4435);
DISPLAY 0.489362 (-4635 4435);
PAINT MONO (-4635 4435);
FORCEPROP 0 LASTPIN (-4650 4375) $PN AE68
J 2
(-4635 4385);
DISPLAY 0.489362 (-4635 4385);
PAINT MONO (-4635 4385);
FORCEPROP 0 LASTPIN (-4650 4325) $PN AE70
J 2
(-4635 4335);
DISPLAY 0.489362 (-4635 4335);
PAINT MONO (-4635 4335);
FORCEPROP 0 LASTPIN (-4650 4275) $PN AE72
J 2
(-4635 4285);
DISPLAY 0.489362 (-4635 4285);
PAINT MONO (-4635 4285);
FORCEPROP 0 LASTPIN (-4650 4225) $PN AE75
J 2
(-4635 4235);
DISPLAY 0.489362 (-4635 4235);
PAINT MONO (-4635 4235);
FORCEPROP 0 LASTPIN (-4650 4175) $PN AF3
J 2
(-4635 4185);
DISPLAY 0.489362 (-4635 4185);
PAINT MONO (-4635 4185);
FORCEPROP 0 LASTPIN (-4650 4125) $PN AF8
J 2
(-4635 4135);
DISPLAY 0.489362 (-4635 4135);
PAINT MONO (-4635 4135);
FORCEPROP 0 LASTPIN (-4650 4075) $PN AF10
J 2
(-4635 4085);
DISPLAY 0.489362 (-4635 4085);
PAINT MONO (-4635 4085);
FORCEPROP 0 LASTPIN (-4650 4025) $PN AF15
J 2
(-4635 4035);
DISPLAY 0.489362 (-4635 4035);
PAINT MONO (-4635 4035);
FORCEPROP 0 LASTPIN (-4650 3975) $PN AF17
J 2
(-4635 3985);
DISPLAY 0.489362 (-4635 3985);
PAINT MONO (-4635 3985);
FORCEPROP 0 LASTPIN (-4650 3925) $PN AF22
J 2
(-4635 3935);
DISPLAY 0.489362 (-4635 3935);
PAINT MONO (-4635 3935);
FORCEPROP 0 LASTPIN (-4650 3875) $PN AF25
J 2
(-4635 3885);
DISPLAY 0.489362 (-4635 3885);
PAINT MONO (-4635 3885);
FORCEPROP 0 LASTPIN (-4650 3825) $PN AF28
J 2
(-4635 3835);
DISPLAY 0.489362 (-4635 3835);
PAINT MONO (-4635 3835);
FORCEPROP 0 LASTPIN (-4650 3775) $PN AF31
J 2
(-4635 3785);
DISPLAY 0.489362 (-4635 3785);
PAINT MONO (-4635 3785);
FORCEPROP 0 LASTPIN (-4650 3725) $PN AF34
J 2
(-4635 3735);
DISPLAY 0.489362 (-4635 3735);
PAINT MONO (-4635 3735);
FORCEPROP 0 LASTPIN (-4650 3675) $PN AF37
J 2
(-4635 3685);
DISPLAY 0.489362 (-4635 3685);
PAINT MONO (-4635 3685);
FORCEPROP 0 LASTPIN (-4650 3625) $PN AF39
J 2
(-4635 3635);
DISPLAY 0.489362 (-4635 3635);
PAINT MONO (-4635 3635);
FORCEPROP 0 LASTPIN (-4650 3575) $PN AF42
J 2
(-4635 3585);
DISPLAY 0.489362 (-4635 3585);
PAINT MONO (-4635 3585);
FORCEPROP 0 LASTPIN (-4650 3525) $PN AF45
J 2
(-4635 3535);
DISPLAY 0.489362 (-4635 3535);
PAINT MONO (-4635 3535);
FORCEPROP 0 LASTPIN (-4650 3475) $PN AF48
J 2
(-4635 3485);
DISPLAY 0.489362 (-4635 3485);
PAINT MONO (-4635 3485);
FORCEPROP 0 LASTPIN (-4650 3425) $PN AF51
J 2
(-4635 3435);
DISPLAY 0.489362 (-4635 3435);
PAINT MONO (-4635 3435);
FORCEPROP 0 LASTPIN (-4650 3375) $PN AF54
J 2
(-4635 3385);
DISPLAY 0.489362 (-4635 3385);
PAINT MONO (-4635 3385);
FORCEPROP 0 LASTPIN (-4650 3325) $PN AF59
J 2
(-4635 3335);
DISPLAY 0.489362 (-4635 3335);
PAINT MONO (-4635 3335);
FORCEPROP 0 LASTPIN (-4650 3275) $PN AF61
J 2
(-4635 3285);
DISPLAY 0.489362 (-4635 3285);
PAINT MONO (-4635 3285);
FORCEPROP 0 LASTPIN (-4650 3225) $PN AF66
J 2
(-4635 3235);
DISPLAY 0.489362 (-4635 3235);
PAINT MONO (-4635 3235);
FORCEPROP 0 LASTPIN (-4650 3175) $PN AF68
J 2
(-4635 3185);
DISPLAY 0.489362 (-4635 3185);
PAINT MONO (-4635 3185);
FORCEPROP 0 LASTPIN (-4650 3125) $PN AF73
J 2
(-4635 3135);
DISPLAY 0.489362 (-4635 3135);
PAINT MONO (-4635 3135);
FORCEPROP 0 LASTPIN (-4650 3075) $PN AG1
J 2
(-4635 3085);
DISPLAY 0.489362 (-4635 3085);
PAINT MONO (-4635 3085);
FORCEPROP 0 LASTPIN (-4650 3025) $PN AG4
J 2
(-4635 3035);
DISPLAY 0.489362 (-4635 3035);
PAINT MONO (-4635 3035);
FORCEPROP 0 LASTPIN (-4650 2975) $PN AG6
J 2
(-4635 2985);
DISPLAY 0.489362 (-4635 2985);
PAINT MONO (-4635 2985);
FORCEPROP 0 LASTPIN (-4650 2925) $PN AG8
J 2
(-4635 2935);
DISPLAY 0.489362 (-4635 2935);
PAINT MONO (-4635 2935);
FORCEPROP 0 LASTPIN (-4650 2875) $PN AG11
J 2
(-4635 2885);
DISPLAY 0.489362 (-4635 2885);
PAINT MONO (-4635 2885);
FORCEPROP 0 LASTPIN (-4650 2825) $PN AG13
J 2
(-4635 2835);
DISPLAY 0.489362 (-4635 2835);
PAINT MONO (-4635 2835);
FORCEPROP 0 LASTPIN (-4650 2775) $PN AG15
J 2
(-4635 2785);
DISPLAY 0.489362 (-4635 2785);
PAINT MONO (-4635 2785);
FORCEPROP 0 LASTPIN (-4650 2725) $PN AG18
J 2
(-4635 2735);
DISPLAY 0.489362 (-4635 2735);
PAINT MONO (-4635 2735);
FORCEPROP 0 LASTPIN (-4650 2675) $PN AG20
J 2
(-4635 2685);
DISPLAY 0.489362 (-4635 2685);
PAINT MONO (-4635 2685);
FORCEPROP 0 LASTPIN (-4650 2625) $PN AG22
J 2
(-4635 2635);
DISPLAY 0.489362 (-4635 2635);
PAINT MONO (-4635 2635);
FORCEPROP 0 LASTPIN (-4650 2575) $PN AG25
J 2
(-4635 2585);
DISPLAY 0.489362 (-4635 2585);
PAINT MONO (-4635 2585);
FORCEPROP 0 LASTPIN (-4650 2525) $PN AG28
J 2
(-4635 2535);
DISPLAY 0.489362 (-4635 2535);
PAINT MONO (-4635 2535);
FORCEPROP 0 LASTPIN (-4650 2475) $PN AG31
J 2
(-4635 2485);
DISPLAY 0.489362 (-4635 2485);
PAINT MONO (-4635 2485);
FORCEPROP 0 LASTPIN (-4650 2425) $PN AG34
J 2
(-4635 2435);
DISPLAY 0.489362 (-4635 2435);
PAINT MONO (-4635 2435);
FORCEPROP 0 LASTPIN (-4650 2375) $PN AG42
J 2
(-4635 2385);
DISPLAY 0.489362 (-4635 2385);
PAINT MONO (-4635 2385);
FORCEPROP 0 LASTPIN (-4650 2325) $PN AG45
J 2
(-4635 2335);
DISPLAY 0.489362 (-4635 2335);
PAINT MONO (-4635 2335);
FORCEPROP 0 LASTPIN (-4650 2275) $PN AG48
J 2
(-4635 2285);
DISPLAY 0.489362 (-4635 2285);
PAINT MONO (-4635 2285);
FORCEPROP 0 LASTPIN (-4650 2225) $PN AG51
J 2
(-4635 2235);
DISPLAY 0.489362 (-4635 2235);
PAINT MONO (-4635 2235);
FORCEPROP 0 LASTPIN (-4650 2175) $PN AG54
J 2
(-4635 2185);
DISPLAY 0.489362 (-4635 2185);
PAINT MONO (-4635 2185);
FORCEPROP 0 LASTPIN (-4650 2125) $PN AG56
J 2
(-4635 2135);
DISPLAY 0.489362 (-4635 2135);
PAINT MONO (-4635 2135);
FORCEPROP 0 LASTPIN (-4650 2075) $PN AG58
J 2
(-4635 2085);
DISPLAY 0.489362 (-4635 2085);
PAINT MONO (-4635 2085);
FORCEPROP 0 LASTPIN (-4650 2025) $PN AG61
J 2
(-4635 2035);
DISPLAY 0.489362 (-4635 2035);
PAINT MONO (-4635 2035);
FORCEPROP 0 LASTPIN (-4650 1975) $PN AG63
J 2
(-4635 1985);
DISPLAY 0.489362 (-4635 1985);
PAINT MONO (-4635 1985);
FORCEPROP 0 LASTPIN (-4650 1925) $PN AG65
J 2
(-4635 1935);
DISPLAY 0.489362 (-4635 1935);
PAINT MONO (-4635 1935);
FORCEPROP 0 LASTPIN (-4650 1875) $PN AG68
J 2
(-4635 1885);
DISPLAY 0.489362 (-4635 1885);
PAINT MONO (-4635 1885);
FORCEPROP 0 LASTPIN (-4650 1825) $PN AG70
J 2
(-4635 1835);
DISPLAY 0.489362 (-4635 1835);
PAINT MONO (-4635 1835);
FORCEPROP 0 LASTPIN (-4650 1775) $PN AG72
J 2
(-4635 1785);
DISPLAY 0.489362 (-4635 1785);
PAINT MONO (-4635 1785);
FORCEPROP 0 LASTPIN (-4650 1725) $PN AG75
J 2
(-4635 1735);
DISPLAY 0.489362 (-4635 1735);
PAINT MONO (-4635 1735);
FORCEPROP 0 LASTPIN (-4650 1675) $PN AH3
J 2
(-4635 1685);
DISPLAY 0.489362 (-4635 1685);
PAINT MONO (-4635 1685);
FORCEPROP 0 LASTPIN (-4650 1625) $PN AH5
J 2
(-4635 1635);
DISPLAY 0.489362 (-4635 1635);
PAINT MONO (-4635 1635);
FORCEPROP 0 LASTPIN (-4650 1575) $PN AH8
J 2
(-4635 1585);
DISPLAY 0.489362 (-4635 1585);
PAINT MONO (-4635 1585);
FORCEPROP 0 LASTPIN (-4650 1525) $PN AH10
J 2
(-4635 1535);
DISPLAY 0.489362 (-4635 1535);
PAINT MONO (-4635 1535);
FORCEPROP 0 LASTPIN (-4650 1475) $PN AH12
J 2
(-4635 1485);
DISPLAY 0.489362 (-4635 1485);
PAINT MONO (-4635 1485);
FORCEPROP 0 LASTPIN (-4650 1425) $PN AH15
J 2
(-4635 1435);
DISPLAY 0.489362 (-4635 1435);
PAINT MONO (-4635 1435);
FORCEPROP 0 LASTPIN (-4650 1375) $PN AH17
J 2
(-4635 1385);
DISPLAY 0.489362 (-4635 1385);
PAINT MONO (-4635 1385);
FORCEPROP 0 LASTPIN (-4650 1325) $PN AH19
J 2
(-4635 1335);
DISPLAY 0.489362 (-4635 1335);
PAINT MONO (-4635 1335);
FORCEPROP 0 LASTPIN (-4650 1275) $PN AH23
J 2
(-4635 1285);
DISPLAY 0.489362 (-4635 1285);
PAINT MONO (-4635 1285);
FORCEPROP 0 LASTPIN (-4650 1225) $PN AH24
J 2
(-4635 1235);
DISPLAY 0.489362 (-4635 1235);
PAINT MONO (-4635 1235);
FORCEPROP 0 LASTPIN (-4650 1175) $PN AH25
J 2
(-4635 1185);
DISPLAY 0.489362 (-4635 1185);
PAINT MONO (-4635 1185);
FORCEPROP 0 LASTPIN (-4650 1125) $PN AH26
J 2
(-4635 1135);
DISPLAY 0.489362 (-4635 1135);
PAINT MONO (-4635 1135);
FORCEPROP 0 LASTPIN (-4650 1075) $PN AH27
J 2
(-4635 1085);
DISPLAY 0.489362 (-4635 1085);
PAINT MONO (-4635 1085);
FORCEPROP 0 LASTPIN (-4650 1025) $PN AH28
J 2
(-4635 1035);
DISPLAY 0.489362 (-4635 1035);
PAINT MONO (-4635 1035);
FORCEPROP 0 LASTPIN (-4650 975) $PN AH29
J 2
(-4635 985);
DISPLAY 0.489362 (-4635 985);
PAINT MONO (-4635 985);
FORCEPROP 0 LASTPIN (-4650 925) $PN AH30
J 2
(-4635 935);
DISPLAY 0.489362 (-4635 935);
PAINT MONO (-4635 935);
FORCEPROP 0 LASTPIN (-4650 875) $PN AH31
J 2
(-4635 885);
DISPLAY 0.489362 (-4635 885);
PAINT MONO (-4635 885);
FORCEPROP 0 LASTPIN (-4650 825) $PN AH32
J 2
(-4635 835);
DISPLAY 0.489362 (-4635 835);
PAINT MONO (-4635 835);
FORCEPROP 0 LASTPIN (-4650 775) $PN AH34
J 2
(-4635 785);
DISPLAY 0.489362 (-4635 785);
PAINT MONO (-4635 785);
FORCEPROP 0 LASTPIN (-4650 725) $PN AH37
J 2
(-4635 735);
DISPLAY 0.489362 (-4635 735);
PAINT MONO (-4635 735);
FORCEPROP 0 LASTPIN (-4650 675) $PN AH39
J 2
(-4635 685);
DISPLAY 0.489362 (-4635 685);
PAINT MONO (-4635 685);
FORCEPROP 0 LASTPIN (-4650 625) $PN AH42
J 2
(-4635 635);
DISPLAY 0.489362 (-4635 635);
PAINT MONO (-4635 635);
FORCEPROP 0 LASTPIN (-4650 575) $PN AH43
J 2
(-4635 585);
DISPLAY 0.489362 (-4635 585);
PAINT MONO (-4635 585);
FORCEPROP 0 LASTPIN (-3550 6375) $PN AH44
J 0
(-3540 6385);
DISPLAY 0.489362 (-3540 6385);
PAINT MONO (-3540 6385);
FORCEPROP 0 LASTPIN (-3550 6325) $PN AH45
J 0
(-3540 6335);
DISPLAY 0.489362 (-3540 6335);
PAINT MONO (-3540 6335);
FORCEPROP 0 LASTPIN (-3550 6275) $PN AH46
J 0
(-3540 6285);
DISPLAY 0.489362 (-3540 6285);
PAINT MONO (-3540 6285);
FORCEPROP 0 LASTPIN (-3550 6225) $PN AH47
J 0
(-3540 6235);
DISPLAY 0.489362 (-3540 6235);
PAINT MONO (-3540 6235);
FORCEPROP 0 LASTPIN (-3550 6175) $PN AH48
J 0
(-3540 6185);
DISPLAY 0.489362 (-3540 6185);
PAINT MONO (-3540 6185);
FORCEPROP 0 LASTPIN (-3550 6125) $PN AH49
J 0
(-3540 6135);
DISPLAY 0.489362 (-3540 6135);
PAINT MONO (-3540 6135);
FORCEPROP 0 LASTPIN (-3550 6075) $PN AH50
J 0
(-3540 6085);
DISPLAY 0.489362 (-3540 6085);
PAINT MONO (-3540 6085);
FORCEPROP 0 LASTPIN (-3550 6025) $PN AH51
J 0
(-3540 6035);
DISPLAY 0.489362 (-3540 6035);
PAINT MONO (-3540 6035);
FORCEPROP 0 LASTPIN (-3550 5975) $PN AH52
J 0
(-3540 5985);
DISPLAY 0.489362 (-3540 5985);
PAINT MONO (-3540 5985);
FORCEPROP 0 LASTPIN (-3550 5925) $PN AH53
J 0
(-3540 5935);
DISPLAY 0.489362 (-3540 5935);
PAINT MONO (-3540 5935);
FORCEPROP 0 LASTPIN (-3550 5875) $PN AH57
J 0
(-3540 5885);
DISPLAY 0.489362 (-3540 5885);
PAINT MONO (-3540 5885);
FORCEPROP 0 LASTPIN (-3550 5825) $PN AH59
J 0
(-3540 5835);
DISPLAY 0.489362 (-3540 5835);
PAINT MONO (-3540 5835);
FORCEPROP 0 LASTPIN (-3550 5775) $PN AH61
J 0
(-3540 5785);
DISPLAY 0.489362 (-3540 5785);
PAINT MONO (-3540 5785);
FORCEPROP 0 LASTPIN (-3550 5725) $PN AH64
J 0
(-3540 5735);
DISPLAY 0.489362 (-3540 5735);
PAINT MONO (-3540 5735);
FORCEPROP 0 LASTPIN (-3550 5675) $PN AH66
J 0
(-3540 5685);
DISPLAY 0.489362 (-3540 5685);
PAINT MONO (-3540 5685);
FORCEPROP 0 LASTPIN (-3550 5625) $PN AH68
J 0
(-3540 5635);
DISPLAY 0.489362 (-3540 5635);
PAINT MONO (-3540 5635);
FORCEPROP 0 LASTPIN (-3550 5575) $PN AH71
J 0
(-3540 5585);
DISPLAY 0.489362 (-3540 5585);
PAINT MONO (-3540 5585);
FORCEPROP 0 LASTPIN (-3550 5525) $PN AH73
J 0
(-3540 5535);
DISPLAY 0.489362 (-3540 5535);
PAINT MONO (-3540 5535);
FORCEPROP 0 LASTPIN (-3550 5475) $PN AJ1
J 0
(-3540 5485);
DISPLAY 0.489362 (-3540 5485);
PAINT MONO (-3540 5485);
FORCEPROP 0 LASTPIN (-3550 5425) $PN AJ6
J 0
(-3540 5435);
DISPLAY 0.489362 (-3540 5435);
PAINT MONO (-3540 5435);
FORCEPROP 0 LASTPIN (-3550 5375) $PN AJ8
J 0
(-3540 5385);
DISPLAY 0.489362 (-3540 5385);
PAINT MONO (-3540 5385);
FORCEPROP 0 LASTPIN (-3550 5325) $PN AJ15
J 0
(-3540 5335);
DISPLAY 0.489362 (-3540 5335);
PAINT MONO (-3540 5335);
FORCEPROP 0 LASTPIN (-3550 5275) $PN AJ20
J 0
(-3540 5285);
DISPLAY 0.489362 (-3540 5285);
PAINT MONO (-3540 5285);
FORCEPROP 0 LASTPIN (-3550 5225) $PN AJ22
J 0
(-3540 5235);
DISPLAY 0.489362 (-3540 5235);
PAINT MONO (-3540 5235);
FORCEPROP 0 LASTPIN (-3550 5175) $PN AJ25
J 0
(-3540 5185);
DISPLAY 0.489362 (-3540 5185);
PAINT MONO (-3540 5185);
FORCEPROP 0 LASTPIN (-3550 5125) $PN AJ28
J 0
(-3540 5135);
DISPLAY 0.489362 (-3540 5135);
PAINT MONO (-3540 5135);
FORCEPROP 0 LASTPIN (-3550 5075) $PN AJ31
J 0
(-3540 5085);
DISPLAY 0.489362 (-3540 5085);
PAINT MONO (-3540 5085);
FORCEPROP 0 LASTPIN (-3550 5025) $PN AJ34
J 0
(-3540 5035);
DISPLAY 0.489362 (-3540 5035);
PAINT MONO (-3540 5035);
FORCEPROP 0 LASTPIN (-3550 4975) $PN AJ35
J 0
(-3540 4985);
DISPLAY 0.489362 (-3540 4985);
PAINT MONO (-3540 4985);
FORCEPROP 0 LASTPIN (-3550 4925) $PN AJ36
J 0
(-3540 4935);
DISPLAY 0.489362 (-3540 4935);
PAINT MONO (-3540 4935);
FORCEPROP 0 LASTPIN (-3550 4875) $PN AJ40
J 0
(-3540 4885);
DISPLAY 0.489362 (-3540 4885);
PAINT MONO (-3540 4885);
FORCEPROP 0 LASTPIN (-3550 4825) $PN AJ41
J 0
(-3540 4835);
DISPLAY 0.489362 (-3540 4835);
PAINT MONO (-3540 4835);
FORCEPROP 0 LASTPIN (-3550 4775) $PN AJ42
J 0
(-3540 4785);
DISPLAY 0.489362 (-3540 4785);
PAINT MONO (-3540 4785);
FORCEPROP 0 LASTPIN (-3550 4725) $PN AJ45
J 0
(-3540 4735);
DISPLAY 0.489362 (-3540 4735);
PAINT MONO (-3540 4735);
FORCEPROP 0 LASTPIN (-3550 4675) $PN AJ48
J 0
(-3540 4685);
DISPLAY 0.489362 (-3540 4685);
PAINT MONO (-3540 4685);
FORCEPROP 0 LASTPIN (-3550 4625) $PN AJ51
J 0
(-3540 4635);
DISPLAY 0.489362 (-3540 4635);
PAINT MONO (-3540 4635);
FORCEPROP 0 LASTPIN (-3550 4575) $PN AJ54
J 0
(-3540 4585);
DISPLAY 0.489362 (-3540 4585);
PAINT MONO (-3540 4585);
FORCEPROP 0 LASTPIN (-3550 4525) $PN AJ56
J 0
(-3540 4535);
DISPLAY 0.489362 (-3540 4535);
PAINT MONO (-3540 4535);
FORCEPROP 0 LASTPIN (-3550 4475) $PN AJ61
J 0
(-3540 4485);
DISPLAY 0.489362 (-3540 4485);
PAINT MONO (-3540 4485);
FORCEPROP 0 LASTPIN (-3550 4425) $PN AJ63
J 0
(-3540 4435);
DISPLAY 0.489362 (-3540 4435);
PAINT MONO (-3540 4435);
FORCEPROP 0 LASTPIN (-3550 4375) $PN AJ68
J 0
(-3540 4385);
DISPLAY 0.489362 (-3540 4385);
PAINT MONO (-3540 4385);
FORCEPROP 0 LASTPIN (-3550 4325) $PN AJ70
J 0
(-3540 4335);
DISPLAY 0.489362 (-3540 4335);
PAINT MONO (-3540 4335);
FORCEPROP 0 LASTPIN (-3550 4275) $PN AJ75
J 0
(-3540 4285);
DISPLAY 0.489362 (-3540 4285);
PAINT MONO (-3540 4285);
FORCEPROP 0 LASTPIN (-3550 4225) $PN AK3
J 0
(-3540 4235);
DISPLAY 0.489362 (-3540 4235);
PAINT MONO (-3540 4235);
FORCEPROP 0 LASTPIN (-3550 4175) $PN AK5
J 0
(-3540 4185);
DISPLAY 0.489362 (-3540 4185);
PAINT MONO (-3540 4185);
FORCEPROP 0 LASTPIN (-3550 4125) $PN AK8
J 0
(-3540 4135);
DISPLAY 0.489362 (-3540 4135);
PAINT MONO (-3540 4135);
FORCEPROP 0 LASTPIN (-3550 4075) $PN AK10
J 0
(-3540 4085);
DISPLAY 0.489362 (-3540 4085);
PAINT MONO (-3540 4085);
FORCEPROP 0 LASTPIN (-3550 4025) $PN AK12
J 0
(-3540 4035);
DISPLAY 0.489362 (-3540 4035);
PAINT MONO (-3540 4035);
FORCEPROP 0 LASTPIN (-3550 3975) $PN AK15
J 0
(-3540 3985);
DISPLAY 0.489362 (-3540 3985);
PAINT MONO (-3540 3985);
FORCEPROP 0 LASTPIN (-3550 3925) $PN AK17
J 0
(-3540 3935);
DISPLAY 0.489362 (-3540 3935);
PAINT MONO (-3540 3935);
FORCEPROP 0 LASTPIN (-3550 3875) $PN AK19
J 0
(-3540 3885);
DISPLAY 0.489362 (-3540 3885);
PAINT MONO (-3540 3885);
FORCEPROP 0 LASTPIN (-3550 3825) $PN AK22
J 0
(-3540 3835);
DISPLAY 0.489362 (-3540 3835);
PAINT MONO (-3540 3835);
FORCEPROP 0 LASTPIN (-3550 3775) $PN AK25
J 0
(-3540 3785);
DISPLAY 0.489362 (-3540 3785);
PAINT MONO (-3540 3785);
FORCEPROP 0 LASTPIN (-3550 3725) $PN AK28
J 0
(-3540 3735);
DISPLAY 0.489362 (-3540 3735);
PAINT MONO (-3540 3735);
FORCEPROP 0 LASTPIN (-3550 3675) $PN AK31
J 0
(-3540 3685);
DISPLAY 0.489362 (-3540 3685);
PAINT MONO (-3540 3685);
FORCEPROP 0 LASTPIN (-3550 3625) $PN AK34
J 0
(-3540 3635);
DISPLAY 0.489362 (-3540 3635);
PAINT MONO (-3540 3635);
FORCEPROP 0 LASTPIN (-3550 3575) $PN AK37
J 0
(-3540 3585);
DISPLAY 0.489362 (-3540 3585);
PAINT MONO (-3540 3585);
FORCEPROP 0 LASTPIN (-3550 3525) $PN AK39
J 0
(-3540 3535);
DISPLAY 0.489362 (-3540 3535);
PAINT MONO (-3540 3535);
FORCEPROP 0 LASTPIN (-3550 3475) $PN AK42
J 0
(-3540 3485);
DISPLAY 0.489362 (-3540 3485);
PAINT MONO (-3540 3485);
FORCEPROP 0 LASTPIN (-3550 3425) $PN AK45
J 0
(-3540 3435);
DISPLAY 0.489362 (-3540 3435);
PAINT MONO (-3540 3435);
FORCEPROP 0 LASTPIN (-3550 3375) $PN AK48
J 0
(-3540 3385);
DISPLAY 0.489362 (-3540 3385);
PAINT MONO (-3540 3385);
FORCEPROP 0 LASTPIN (-3550 3325) $PN AK51
J 0
(-3540 3335);
DISPLAY 0.489362 (-3540 3335);
PAINT MONO (-3540 3335);
FORCEPROP 0 LASTPIN (-3550 3275) $PN AK54
J 0
(-3540 3285);
DISPLAY 0.489362 (-3540 3285);
PAINT MONO (-3540 3285);
FORCEPROP 0 LASTPIN (-3550 3225) $PN AK57
J 0
(-3540 3235);
DISPLAY 0.489362 (-3540 3235);
PAINT MONO (-3540 3235);
FORCEPROP 0 LASTPIN (-3550 3175) $PN AK59
J 0
(-3540 3185);
DISPLAY 0.489362 (-3540 3185);
PAINT MONO (-3540 3185);
FORCEPROP 0 LASTPIN (-3550 3125) $PN AK61
J 0
(-3540 3135);
DISPLAY 0.489362 (-3540 3135);
PAINT MONO (-3540 3135);
FORCEPROP 0 LASTPIN (-3550 3075) $PN AK64
J 0
(-3540 3085);
DISPLAY 0.489362 (-3540 3085);
PAINT MONO (-3540 3085);
FORCEPROP 0 LASTPIN (-3550 3025) $PN AK66
J 0
(-3540 3035);
DISPLAY 0.489362 (-3540 3035);
PAINT MONO (-3540 3035);
FORCEPROP 0 LASTPIN (-3550 2975) $PN AK68
J 0
(-3540 2985);
DISPLAY 0.489362 (-3540 2985);
PAINT MONO (-3540 2985);
FORCEPROP 0 LASTPIN (-3550 2925) $PN AK71
J 0
(-3540 2935);
DISPLAY 0.489362 (-3540 2935);
PAINT MONO (-3540 2935);
FORCEPROP 0 LASTPIN (-3550 2875) $PN AK73
J 0
(-3540 2885);
DISPLAY 0.489362 (-3540 2885);
PAINT MONO (-3540 2885);
FORCEPROP 0 LASTPIN (-3550 2825) $PN AL1
J 0
(-3540 2835);
DISPLAY 0.489362 (-3540 2835);
PAINT MONO (-3540 2835);
FORCEPROP 0 LASTPIN (-3550 2775) $PN AL4
J 0
(-3540 2785);
DISPLAY 0.489362 (-3540 2785);
PAINT MONO (-3540 2785);
FORCEPROP 0 LASTPIN (-3550 2725) $PN AL6
J 0
(-3540 2735);
DISPLAY 0.489362 (-3540 2735);
PAINT MONO (-3540 2735);
FORCEPROP 0 LASTPIN (-3550 2675) $PN AL8
J 0
(-3540 2685);
DISPLAY 0.489362 (-3540 2685);
PAINT MONO (-3540 2685);
FORCEPROP 0 LASTPIN (-3550 2625) $PN AL11
J 0
(-3540 2635);
DISPLAY 0.489362 (-3540 2635);
PAINT MONO (-3540 2635);
FORCEPROP 0 LASTPIN (-3550 2575) $PN AL13
J 0
(-3540 2585);
DISPLAY 0.489362 (-3540 2585);
PAINT MONO (-3540 2585);
FORCEPROP 0 LASTPIN (-3550 2525) $PN AL15
J 0
(-3540 2535);
DISPLAY 0.489362 (-3540 2535);
PAINT MONO (-3540 2535);
FORCEPROP 0 LASTPIN (-3550 2475) $PN AL18
J 0
(-3540 2485);
DISPLAY 0.489362 (-3540 2485);
PAINT MONO (-3540 2485);
FORCEPROP 0 LASTPIN (-3550 2425) $PN AL20
J 0
(-3540 2435);
DISPLAY 0.489362 (-3540 2435);
PAINT MONO (-3540 2435);
FORCEPROP 0 LASTPIN (-3550 2375) $PN AL22
J 0
(-3540 2385);
DISPLAY 0.489362 (-3540 2385);
PAINT MONO (-3540 2385);
FORCEPROP 0 LASTPIN (-3550 2325) $PN AL25
J 0
(-3540 2335);
DISPLAY 0.489362 (-3540 2335);
PAINT MONO (-3540 2335);
FORCEPROP 0 LASTPIN (-3550 2275) $PN AL28
J 0
(-3540 2285);
DISPLAY 0.489362 (-3540 2285);
PAINT MONO (-3540 2285);
FORCEPROP 0 LASTPIN (-3550 2225) $PN AL31
J 0
(-3540 2235);
DISPLAY 0.489362 (-3540 2235);
PAINT MONO (-3540 2235);
FORCEPROP 0 LASTPIN (-3550 2175) $PN AL34
J 0
(-3540 2185);
DISPLAY 0.489362 (-3540 2185);
PAINT MONO (-3540 2185);
FORCEPROP 0 LASTPIN (-3550 2125) $PN AL42
J 0
(-3540 2135);
DISPLAY 0.489362 (-3540 2135);
PAINT MONO (-3540 2135);
FORCEPROP 0 LASTPIN (-3550 2075) $PN AL45
J 0
(-3540 2085);
DISPLAY 0.489362 (-3540 2085);
PAINT MONO (-3540 2085);
FORCEPROP 0 LASTPIN (-3550 2025) $PN AL48
J 0
(-3540 2035);
DISPLAY 0.489362 (-3540 2035);
PAINT MONO (-3540 2035);
FORCEPROP 0 LASTPIN (-3550 1975) $PN AL51
J 0
(-3540 1985);
DISPLAY 0.489362 (-3540 1985);
PAINT MONO (-3540 1985);
FORCEPROP 0 LASTPIN (-3550 1925) $PN AL54
J 0
(-3540 1935);
DISPLAY 0.489362 (-3540 1935);
PAINT MONO (-3540 1935);
FORCEPROP 0 LASTPIN (-3550 1875) $PN AL56
J 0
(-3540 1885);
DISPLAY 0.489362 (-3540 1885);
PAINT MONO (-3540 1885);
FORCEPROP 0 LASTPIN (-3550 1825) $PN AL58
J 0
(-3540 1835);
DISPLAY 0.489362 (-3540 1835);
PAINT MONO (-3540 1835);
FORCEPROP 0 LASTPIN (-3550 1775) $PN AL61
J 0
(-3540 1785);
DISPLAY 0.489362 (-3540 1785);
PAINT MONO (-3540 1785);
FORCEPROP 0 LASTPIN (-3550 1725) $PN AL63
J 0
(-3540 1735);
DISPLAY 0.489362 (-3540 1735);
PAINT MONO (-3540 1735);
FORCEPROP 0 LASTPIN (-3550 1675) $PN AL65
J 0
(-3540 1685);
DISPLAY 0.489362 (-3540 1685);
PAINT MONO (-3540 1685);
FORCEPROP 0 LASTPIN (-3550 1625) $PN AL68
J 0
(-3540 1635);
DISPLAY 0.489362 (-3540 1635);
PAINT MONO (-3540 1635);
FORCEPROP 0 LASTPIN (-3550 1575) $PN AL70
J 0
(-3540 1585);
DISPLAY 0.489362 (-3540 1585);
PAINT MONO (-3540 1585);
FORCEPROP 0 LASTPIN (-3550 1525) $PN AL72
J 0
(-3540 1535);
DISPLAY 0.489362 (-3540 1535);
PAINT MONO (-3540 1535);
FORCEPROP 0 LASTPIN (-3550 1475) $PN AL75
J 0
(-3540 1485);
DISPLAY 0.489362 (-3540 1485);
PAINT MONO (-3540 1485);
FORCEPROP 0 LASTPIN (-3550 1425) $PN AM3
J 0
(-3540 1435);
DISPLAY 0.489362 (-3540 1435);
PAINT MONO (-3540 1435);
FORCEPROP 0 LASTPIN (-3550 1375) $PN AM8
J 0
(-3540 1385);
DISPLAY 0.489362 (-3540 1385);
PAINT MONO (-3540 1385);
FORCEPROP 0 LASTPIN (-3550 1325) $PN AM10
J 0
(-3540 1335);
DISPLAY 0.489362 (-3540 1335);
PAINT MONO (-3540 1335);
FORCEPROP 0 LASTPIN (-3550 1275) $PN AM15
J 0
(-3540 1285);
DISPLAY 0.489362 (-3540 1285);
PAINT MONO (-3540 1285);
FORCEPROP 0 LASTPIN (-3550 1225) $PN AM17
J 0
(-3540 1235);
DISPLAY 0.489362 (-3540 1235);
PAINT MONO (-3540 1235);
FORCEPROP 0 LASTPIN (-3550 1175) $PN AM23
J 0
(-3540 1185);
DISPLAY 0.489362 (-3540 1185);
PAINT MONO (-3540 1185);
FORCEPROP 0 LASTPIN (-3550 1125) $PN AM24
J 0
(-3540 1135);
DISPLAY 0.489362 (-3540 1135);
PAINT MONO (-3540 1135);
FORCEPROP 0 LASTPIN (-3550 1075) $PN AM25
J 0
(-3540 1085);
DISPLAY 0.489362 (-3540 1085);
PAINT MONO (-3540 1085);
FORCEPROP 0 LASTPIN (-3550 1025) $PN AM26
J 0
(-3540 1035);
DISPLAY 0.489362 (-3540 1035);
PAINT MONO (-3540 1035);
FORCEPROP 0 LASTPIN (-3550 975) $PN AM27
J 0
(-3540 985);
DISPLAY 0.489362 (-3540 985);
PAINT MONO (-3540 985);
FORCEPROP 0 LASTPIN (-3550 925) $PN AM28
J 0
(-3540 935);
DISPLAY 0.489362 (-3540 935);
PAINT MONO (-3540 935);
FORCEPROP 0 LASTPIN (-3550 875) $PN AM29
J 0
(-3540 885);
DISPLAY 0.489362 (-3540 885);
PAINT MONO (-3540 885);
FORCEPROP 0 LASTPIN (-3550 825) $PN AM30
J 0
(-3540 835);
DISPLAY 0.489362 (-3540 835);
PAINT MONO (-3540 835);
FORCEPROP 0 LASTPIN (-3550 775) $PN AM31
J 0
(-3540 785);
DISPLAY 0.489362 (-3540 785);
PAINT MONO (-3540 785);
FORCEPROP 0 LASTPIN (-3550 725) $PN AM32
J 0
(-3540 735);
DISPLAY 0.489362 (-3540 735);
PAINT MONO (-3540 735);
FORCEPROP 0 LASTPIN (-3550 675) $PN AM33
J 0
(-3540 685);
DISPLAY 0.489362 (-3540 685);
PAINT MONO (-3540 685);
FORCEPROP 0 LASTPIN (-3550 625) $PN AM34
J 0
(-3540 635);
DISPLAY 0.489362 (-3540 635);
PAINT MONO (-3540 635);
FORCEPROP 0 LASTPIN (-3550 575) $PN AM39
J 0
(-3540 585);
DISPLAY 0.489362 (-3540 585);
PAINT MONO (-3540 585);
FORCEPROP 2 LAST PART_TYPE SMLF
J 0
(-4500 6700);
DISPLAY 1.021277 (-4500 6700);
FORCEPROP 1 LAST MATERIAL IO
J 0
(-4495 6557);
DISPLAY 0.489362 (-4495 6557);
PAINT SKYBLUE (-4495 6557);
FORCEPROP 2 LAST VALUE SOCKET6096_13568-001
J 0
(-4350 6550);
DISPLAY 0.489362 (-4350 6550);
PAINT SKYBLUE (-4350 6550);
FORCEPROP 1 LAST NEEDS_NO_SIZE TRUE
J 0
(-4100 3475);
DISPLAY 0.723404 (-4100 3475);
PAINT GREEN (-4100 3475);
DISPLAY INVISIBLE (-4100 3475);
FORCEPROP 1 LAST CDS_LMAN_SYM_OUTLINE -400,3050,400,-3050
J 0
(-4100 3475);
DISPLAY 0.468085 (-4100 3475);
PAINT GREEN (-4100 3475);
DISPLAY INVISIBLE (-4100 3475);
FORCEPROP 2 LAST CDS_LIB pure_quanta
J 0
(-4100 3475);
DISPLAY INVISIBLE (-4100 3475);
FORCEPROP 1 LAST PATH I22
J 0
(-4100 3475);
DISPLAY 0.723404 (-4100 3475);
PAINT GREEN (-4100 3475);
DISPLAY INVISIBLE (-4100 3475);
FORCEPROP 1 LAST PART_NUMBER DGA^6000030
J 0
(-4500 6650);
DISPLAY 0.489362 (-4500 6650);
PAINT SKYBLUE (-4500 6650);
DISPLAY INVISIBLE (-4500 6650);
FORCEADD GENOA_SP5..32
(-2625 3475);
FORCEPROP 1 LAST LOCATION U25
J 0
(-3020 6600);
DISPLAY 0.489362 (-3020 6600);
PAINT SKYBLUE (-3020 6600);
FORCEPROP 0 LAST $SEC 32
J 0
(-3000 6875);
DISPLAY 0.680851 (-3000 6875);
PAINT MONO (-3000 6875);
DISPLAY INVISIBLE (-3000 6875);
FORCEPROP 0 LAST CDS_SEC 32
J 0
(-3225 6725);
DISPLAY 1.021277 (-3225 6725);
DISPLAY INVISIBLE (-3225 6725);
FORCEPROP 0 LASTPIN (-3175 6375) $PN AM42
J 2
(-3135 6385);
DISPLAY 0.489362 (-3135 6385);
PAINT MONO (-3135 6385);
FORCEPROP 0 LASTPIN (-3175 6325) $PN AM43
J 2
(-3135 6335);
DISPLAY 0.489362 (-3135 6335);
PAINT MONO (-3135 6335);
FORCEPROP 0 LASTPIN (-3175 6275) $PN AM44
J 2
(-3135 6285);
DISPLAY 0.489362 (-3135 6285);
PAINT MONO (-3135 6285);
FORCEPROP 0 LASTPIN (-3175 6225) $PN AM45
J 2
(-3135 6235);
DISPLAY 0.489362 (-3135 6235);
PAINT MONO (-3135 6235);
FORCEPROP 0 LASTPIN (-3175 6175) $PN AM46
J 2
(-3135 6185);
DISPLAY 0.489362 (-3135 6185);
PAINT MONO (-3135 6185);
FORCEPROP 0 LASTPIN (-3175 6125) $PN AM47
J 2
(-3135 6135);
DISPLAY 0.489362 (-3135 6135);
PAINT MONO (-3135 6135);
FORCEPROP 0 LASTPIN (-3175 6075) $PN AM48
J 2
(-3135 6085);
DISPLAY 0.489362 (-3135 6085);
PAINT MONO (-3135 6085);
FORCEPROP 0 LASTPIN (-3175 6025) $PN AM49
J 2
(-3135 6035);
DISPLAY 0.489362 (-3135 6035);
PAINT MONO (-3135 6035);
FORCEPROP 0 LASTPIN (-3175 5975) $PN AM50
J 2
(-3135 5985);
DISPLAY 0.489362 (-3135 5985);
PAINT MONO (-3135 5985);
FORCEPROP 0 LASTPIN (-3175 5925) $PN AM51
J 2
(-3135 5935);
DISPLAY 0.489362 (-3135 5935);
PAINT MONO (-3135 5935);
FORCEPROP 0 LASTPIN (-3175 5875) $PN AM52
J 2
(-3135 5885);
DISPLAY 0.489362 (-3135 5885);
PAINT MONO (-3135 5885);
FORCEPROP 0 LASTPIN (-3175 5825) $PN AM53
J 2
(-3135 5835);
DISPLAY 0.489362 (-3135 5835);
PAINT MONO (-3135 5835);
FORCEPROP 0 LASTPIN (-3175 5775) $PN AM59
J 2
(-3135 5785);
DISPLAY 0.489362 (-3135 5785);
PAINT MONO (-3135 5785);
FORCEPROP 0 LASTPIN (-3175 5725) $PN AM61
J 2
(-3135 5735);
DISPLAY 0.489362 (-3135 5735);
PAINT MONO (-3135 5735);
FORCEPROP 0 LASTPIN (-3175 5675) $PN AM66
J 2
(-3135 5685);
DISPLAY 0.489362 (-3135 5685);
PAINT MONO (-3135 5685);
FORCEPROP 0 LASTPIN (-3175 5625) $PN AM68
J 2
(-3135 5635);
DISPLAY 0.489362 (-3135 5635);
PAINT MONO (-3135 5635);
FORCEPROP 0 LASTPIN (-3175 5575) $PN AM73
J 2
(-3135 5585);
DISPLAY 0.489362 (-3135 5585);
PAINT MONO (-3135 5585);
FORCEPROP 0 LASTPIN (-3175 5525) $PN AN1
J 2
(-3135 5535);
DISPLAY 0.489362 (-3135 5535);
PAINT MONO (-3135 5535);
FORCEPROP 0 LASTPIN (-3175 5475) $PN AN4
J 2
(-3135 5485);
DISPLAY 0.489362 (-3135 5485);
PAINT MONO (-3135 5485);
FORCEPROP 0 LASTPIN (-3175 5425) $PN AN6
J 2
(-3135 5435);
DISPLAY 0.489362 (-3135 5435);
PAINT MONO (-3135 5435);
FORCEPROP 0 LASTPIN (-3175 5375) $PN AN8
J 2
(-3135 5385);
DISPLAY 0.489362 (-3135 5385);
PAINT MONO (-3135 5385);
FORCEPROP 0 LASTPIN (-3175 5325) $PN AN11
J 2
(-3135 5335);
DISPLAY 0.489362 (-3135 5335);
PAINT MONO (-3135 5335);
FORCEPROP 0 LASTPIN (-3175 5275) $PN AN13
J 2
(-3135 5285);
DISPLAY 0.489362 (-3135 5285);
PAINT MONO (-3135 5285);
FORCEPROP 0 LASTPIN (-3175 5225) $PN AN15
J 2
(-3135 5235);
DISPLAY 0.489362 (-3135 5235);
PAINT MONO (-3135 5235);
FORCEPROP 0 LASTPIN (-3175 5175) $PN AN18
J 2
(-3135 5185);
DISPLAY 0.489362 (-3135 5185);
PAINT MONO (-3135 5185);
FORCEPROP 0 LASTPIN (-3175 5125) $PN AN22
J 2
(-3135 5135);
DISPLAY 0.489362 (-3135 5135);
PAINT MONO (-3135 5135);
FORCEPROP 0 LASTPIN (-3175 5075) $PN AN25
J 2
(-3135 5085);
DISPLAY 0.489362 (-3135 5085);
PAINT MONO (-3135 5085);
FORCEPROP 0 LASTPIN (-3175 5025) $PN AN28
J 2
(-3135 5035);
DISPLAY 0.489362 (-3135 5035);
PAINT MONO (-3135 5035);
FORCEPROP 0 LASTPIN (-3175 4975) $PN AN31
J 2
(-3135 4985);
DISPLAY 0.489362 (-3135 4985);
PAINT MONO (-3135 4985);
FORCEPROP 0 LASTPIN (-3175 4925) $PN AN34
J 2
(-3135 4935);
DISPLAY 0.489362 (-3135 4935);
PAINT MONO (-3135 4935);
FORCEPROP 0 LASTPIN (-3175 4875) $PN AN35
J 2
(-3135 4885);
DISPLAY 0.489362 (-3135 4885);
PAINT MONO (-3135 4885);
FORCEPROP 0 LASTPIN (-3175 4825) $PN AN36
J 2
(-3135 4835);
DISPLAY 0.489362 (-3135 4835);
PAINT MONO (-3135 4835);
FORCEPROP 0 LASTPIN (-3175 4775) $PN AN40
J 2
(-3135 4785);
DISPLAY 0.489362 (-3135 4785);
PAINT MONO (-3135 4785);
FORCEPROP 0 LASTPIN (-3175 4725) $PN AN41
J 2
(-3135 4735);
DISPLAY 0.489362 (-3135 4735);
PAINT MONO (-3135 4735);
FORCEPROP 0 LASTPIN (-3175 4675) $PN AN42
J 2
(-3135 4685);
DISPLAY 0.489362 (-3135 4685);
PAINT MONO (-3135 4685);
FORCEPROP 0 LASTPIN (-3175 4625) $PN AN45
J 2
(-3135 4635);
DISPLAY 0.489362 (-3135 4635);
PAINT MONO (-3135 4635);
FORCEPROP 0 LASTPIN (-3175 4575) $PN AN48
J 2
(-3135 4585);
DISPLAY 0.489362 (-3135 4585);
PAINT MONO (-3135 4585);
FORCEPROP 0 LASTPIN (-3175 4525) $PN AN51
J 2
(-3135 4535);
DISPLAY 0.489362 (-3135 4535);
PAINT MONO (-3135 4535);
FORCEPROP 0 LASTPIN (-3175 4475) $PN AN54
J 2
(-3135 4485);
DISPLAY 0.489362 (-3135 4485);
PAINT MONO (-3135 4485);
FORCEPROP 0 LASTPIN (-3175 4425) $PN AN56
J 2
(-3135 4435);
DISPLAY 0.489362 (-3135 4435);
PAINT MONO (-3135 4435);
FORCEPROP 0 LASTPIN (-3175 4375) $PN AN58
J 2
(-3135 4385);
DISPLAY 0.489362 (-3135 4385);
PAINT MONO (-3135 4385);
FORCEPROP 0 LASTPIN (-3175 4325) $PN AN61
J 2
(-3135 4335);
DISPLAY 0.489362 (-3135 4335);
PAINT MONO (-3135 4335);
FORCEPROP 0 LASTPIN (-3175 4275) $PN AN63
J 2
(-3135 4285);
DISPLAY 0.489362 (-3135 4285);
PAINT MONO (-3135 4285);
FORCEPROP 0 LASTPIN (-3175 4225) $PN AN65
J 2
(-3135 4235);
DISPLAY 0.489362 (-3135 4235);
PAINT MONO (-3135 4235);
FORCEPROP 0 LASTPIN (-3175 4175) $PN AN68
J 2
(-3135 4185);
DISPLAY 0.489362 (-3135 4185);
PAINT MONO (-3135 4185);
FORCEPROP 0 LASTPIN (-3175 4125) $PN AN70
J 2
(-3135 4135);
DISPLAY 0.489362 (-3135 4135);
PAINT MONO (-3135 4135);
FORCEPROP 0 LASTPIN (-3175 4075) $PN AN72
J 2
(-3135 4085);
DISPLAY 0.489362 (-3135 4085);
PAINT MONO (-3135 4085);
FORCEPROP 0 LASTPIN (-3175 4025) $PN AN75
J 2
(-3135 4035);
DISPLAY 0.489362 (-3135 4035);
PAINT MONO (-3135 4035);
FORCEPROP 0 LASTPIN (-3175 3975) $PN AP3
J 2
(-3135 3985);
DISPLAY 0.489362 (-3135 3985);
PAINT MONO (-3135 3985);
FORCEPROP 0 LASTPIN (-3175 3925) $PN AP5
J 2
(-3135 3935);
DISPLAY 0.489362 (-3135 3935);
PAINT MONO (-3135 3935);
FORCEPROP 0 LASTPIN (-3175 3875) $PN AP8
J 2
(-3135 3885);
DISPLAY 0.489362 (-3135 3885);
PAINT MONO (-3135 3885);
FORCEPROP 0 LASTPIN (-3175 3825) $PN AP10
J 2
(-3135 3835);
DISPLAY 0.489362 (-3135 3835);
PAINT MONO (-3135 3835);
FORCEPROP 0 LASTPIN (-3175 3775) $PN AP12
J 2
(-3135 3785);
DISPLAY 0.489362 (-3135 3785);
PAINT MONO (-3135 3785);
FORCEPROP 0 LASTPIN (-3175 3725) $PN AP15
J 2
(-3135 3735);
DISPLAY 0.489362 (-3135 3735);
PAINT MONO (-3135 3735);
FORCEPROP 0 LASTPIN (-3175 3675) $PN AP17
J 2
(-3135 3685);
DISPLAY 0.489362 (-3135 3685);
PAINT MONO (-3135 3685);
FORCEPROP 0 LASTPIN (-3175 3625) $PN AP19
J 2
(-3135 3635);
DISPLAY 0.489362 (-3135 3635);
PAINT MONO (-3135 3635);
FORCEPROP 0 LASTPIN (-3175 3575) $PN AP22
J 2
(-3135 3585);
DISPLAY 0.489362 (-3135 3585);
PAINT MONO (-3135 3585);
FORCEPROP 0 LASTPIN (-3175 3525) $PN AP25
J 2
(-3135 3535);
DISPLAY 0.489362 (-3135 3535);
PAINT MONO (-3135 3535);
FORCEPROP 0 LASTPIN (-3175 3475) $PN AP28
J 2
(-3135 3485);
DISPLAY 0.489362 (-3135 3485);
PAINT MONO (-3135 3485);
FORCEPROP 0 LASTPIN (-3175 3425) $PN AP31
J 2
(-3135 3435);
DISPLAY 0.489362 (-3135 3435);
PAINT MONO (-3135 3435);
FORCEPROP 0 LASTPIN (-3175 3375) $PN AP34
J 2
(-3135 3385);
DISPLAY 0.489362 (-3135 3385);
PAINT MONO (-3135 3385);
FORCEPROP 0 LASTPIN (-3175 3325) $PN AP37
J 2
(-3135 3335);
DISPLAY 0.489362 (-3135 3335);
PAINT MONO (-3135 3335);
FORCEPROP 0 LASTPIN (-3175 3275) $PN AP39
J 2
(-3135 3285);
DISPLAY 0.489362 (-3135 3285);
PAINT MONO (-3135 3285);
FORCEPROP 0 LASTPIN (-3175 3225) $PN AP42
J 2
(-3135 3235);
DISPLAY 0.489362 (-3135 3235);
PAINT MONO (-3135 3235);
FORCEPROP 0 LASTPIN (-3175 3175) $PN AP45
J 2
(-3135 3185);
DISPLAY 0.489362 (-3135 3185);
PAINT MONO (-3135 3185);
FORCEPROP 0 LASTPIN (-3175 3125) $PN AP48
J 2
(-3135 3135);
DISPLAY 0.489362 (-3135 3135);
PAINT MONO (-3135 3135);
FORCEPROP 0 LASTPIN (-3175 3075) $PN AP51
J 2
(-3135 3085);
DISPLAY 0.489362 (-3135 3085);
PAINT MONO (-3135 3085);
FORCEPROP 0 LASTPIN (-3175 3025) $PN AP54
J 2
(-3135 3035);
DISPLAY 0.489362 (-3135 3035);
PAINT MONO (-3135 3035);
FORCEPROP 0 LASTPIN (-3175 2975) $PN AP57
J 2
(-3135 2985);
DISPLAY 0.489362 (-3135 2985);
PAINT MONO (-3135 2985);
FORCEPROP 0 LASTPIN (-3175 2925) $PN AP59
J 2
(-3135 2935);
DISPLAY 0.489362 (-3135 2935);
PAINT MONO (-3135 2935);
FORCEPROP 0 LASTPIN (-3175 2875) $PN AP61
J 2
(-3135 2885);
DISPLAY 0.489362 (-3135 2885);
PAINT MONO (-3135 2885);
FORCEPROP 0 LASTPIN (-3175 2825) $PN AP64
J 2
(-3135 2835);
DISPLAY 0.489362 (-3135 2835);
PAINT MONO (-3135 2835);
FORCEPROP 0 LASTPIN (-3175 2775) $PN AP66
J 2
(-3135 2785);
DISPLAY 0.489362 (-3135 2785);
PAINT MONO (-3135 2785);
FORCEPROP 0 LASTPIN (-3175 2725) $PN AP68
J 2
(-3135 2735);
DISPLAY 0.489362 (-3135 2735);
PAINT MONO (-3135 2735);
FORCEPROP 0 LASTPIN (-3175 2675) $PN AP71
J 2
(-3135 2685);
DISPLAY 0.489362 (-3135 2685);
PAINT MONO (-3135 2685);
FORCEPROP 0 LASTPIN (-3175 2625) $PN AP73
J 2
(-3135 2635);
DISPLAY 0.489362 (-3135 2635);
PAINT MONO (-3135 2635);
FORCEPROP 0 LASTPIN (-3175 2575) $PN AR1
J 2
(-3135 2585);
DISPLAY 0.489362 (-3135 2585);
PAINT MONO (-3135 2585);
FORCEPROP 0 LASTPIN (-3175 2525) $PN AR5
J 2
(-3135 2535);
DISPLAY 0.489362 (-3135 2535);
PAINT MONO (-3135 2535);
FORCEPROP 0 LASTPIN (-3175 2475) $PN AR6
J 2
(-3135 2485);
DISPLAY 0.489362 (-3135 2485);
PAINT MONO (-3135 2485);
FORCEPROP 0 LASTPIN (-3175 2425) $PN AR8
J 2
(-3135 2435);
DISPLAY 0.489362 (-3135 2435);
PAINT MONO (-3135 2435);
FORCEPROP 0 LASTPIN (-3175 2375) $PN AR9
J 2
(-3135 2385);
DISPLAY 0.489362 (-3135 2385);
PAINT MONO (-3135 2385);
FORCEPROP 0 LASTPIN (-3175 2325) $PN AR12
J 2
(-3135 2335);
DISPLAY 0.489362 (-3135 2335);
PAINT MONO (-3135 2335);
FORCEPROP 0 LASTPIN (-3175 2275) $PN AR13
J 2
(-3135 2285);
DISPLAY 0.489362 (-3135 2285);
PAINT MONO (-3135 2285);
FORCEPROP 0 LASTPIN (-3175 2225) $PN AR15
J 2
(-3135 2235);
DISPLAY 0.489362 (-3135 2235);
PAINT MONO (-3135 2235);
FORCEPROP 0 LASTPIN (-3175 2175) $PN AR16
J 2
(-3135 2185);
DISPLAY 0.489362 (-3135 2185);
PAINT MONO (-3135 2185);
FORCEPROP 0 LASTPIN (-3175 2125) $PN AR19
J 2
(-3135 2135);
DISPLAY 0.489362 (-3135 2135);
PAINT MONO (-3135 2135);
FORCEPROP 0 LASTPIN (-3175 2075) $PN AR20
J 2
(-3135 2085);
DISPLAY 0.489362 (-3135 2085);
PAINT MONO (-3135 2085);
FORCEPROP 0 LASTPIN (-3175 2025) $PN AR22
J 2
(-3135 2035);
DISPLAY 0.489362 (-3135 2035);
PAINT MONO (-3135 2035);
FORCEPROP 0 LASTPIN (-3175 1975) $PN AR24
J 2
(-3135 1985);
DISPLAY 0.489362 (-3135 1985);
PAINT MONO (-3135 1985);
FORCEPROP 0 LASTPIN (-3175 1925) $PN AR26
J 2
(-3135 1935);
DISPLAY 0.489362 (-3135 1935);
PAINT MONO (-3135 1935);
FORCEPROP 0 LASTPIN (-3175 1875) $PN AR28
J 2
(-3135 1885);
DISPLAY 0.489362 (-3135 1885);
PAINT MONO (-3135 1885);
FORCEPROP 0 LASTPIN (-3175 1825) $PN AR30
J 2
(-3135 1835);
DISPLAY 0.489362 (-3135 1835);
PAINT MONO (-3135 1835);
FORCEPROP 0 LASTPIN (-3175 1775) $PN AR32
J 2
(-3135 1785);
DISPLAY 0.489362 (-3135 1785);
PAINT MONO (-3135 1785);
FORCEPROP 0 LASTPIN (-3175 1725) $PN AR34
J 2
(-3135 1735);
DISPLAY 0.489362 (-3135 1735);
PAINT MONO (-3135 1735);
FORCEPROP 0 LASTPIN (-3175 1675) $PN AR36
J 2
(-3135 1685);
DISPLAY 0.489362 (-3135 1685);
PAINT MONO (-3135 1685);
FORCEPROP 0 LASTPIN (-3175 1625) $PN AR41
J 2
(-3135 1635);
DISPLAY 0.489362 (-3135 1635);
PAINT MONO (-3135 1635);
FORCEPROP 0 LASTPIN (-3175 1575) $PN AR43
J 2
(-3135 1585);
DISPLAY 0.489362 (-3135 1585);
PAINT MONO (-3135 1585);
FORCEPROP 0 LASTPIN (-3175 1525) $PN AR45
J 2
(-3135 1535);
DISPLAY 0.489362 (-3135 1535);
PAINT MONO (-3135 1535);
FORCEPROP 0 LASTPIN (-3175 1475) $PN AR47
J 2
(-3135 1485);
DISPLAY 0.489362 (-3135 1485);
PAINT MONO (-3135 1485);
FORCEPROP 0 LASTPIN (-3175 1425) $PN AR49
J 2
(-3135 1435);
DISPLAY 0.489362 (-3135 1435);
PAINT MONO (-3135 1435);
FORCEPROP 0 LASTPIN (-3175 1375) $PN AR51
J 2
(-3135 1385);
DISPLAY 0.489362 (-3135 1385);
PAINT MONO (-3135 1385);
FORCEPROP 0 LASTPIN (-3175 1325) $PN AR53
J 2
(-3135 1335);
DISPLAY 0.489362 (-3135 1335);
PAINT MONO (-3135 1335);
FORCEPROP 0 LASTPIN (-3175 1275) $PN AR56
J 2
(-3135 1285);
DISPLAY 0.489362 (-3135 1285);
PAINT MONO (-3135 1285);
FORCEPROP 0 LASTPIN (-3175 1225) $PN AR57
J 2
(-3135 1235);
DISPLAY 0.489362 (-3135 1235);
PAINT MONO (-3135 1235);
FORCEPROP 0 LASTPIN (-3175 1175) $PN AR60
J 2
(-3135 1185);
DISPLAY 0.489362 (-3135 1185);
PAINT MONO (-3135 1185);
FORCEPROP 0 LASTPIN (-3175 1125) $PN AR61
J 2
(-3135 1135);
DISPLAY 0.489362 (-3135 1135);
PAINT MONO (-3135 1135);
FORCEPROP 0 LASTPIN (-3175 1075) $PN AR63
J 2
(-3135 1085);
DISPLAY 0.489362 (-3135 1085);
PAINT MONO (-3135 1085);
FORCEPROP 0 LASTPIN (-3175 1025) $PN AR64
J 2
(-3135 1035);
DISPLAY 0.489362 (-3135 1035);
PAINT MONO (-3135 1035);
FORCEPROP 0 LASTPIN (-3175 975) $PN AR67
J 2
(-3135 985);
DISPLAY 0.489362 (-3135 985);
PAINT MONO (-3135 985);
FORCEPROP 0 LASTPIN (-3175 925) $PN AR68
J 2
(-3135 935);
DISPLAY 0.489362 (-3135 935);
PAINT MONO (-3135 935);
FORCEPROP 0 LASTPIN (-3175 875) $PN AR70
J 2
(-3135 885);
DISPLAY 0.489362 (-3135 885);
PAINT MONO (-3135 885);
FORCEPROP 0 LASTPIN (-3175 825) $PN AR71
J 2
(-3135 835);
DISPLAY 0.489362 (-3135 835);
PAINT MONO (-3135 835);
FORCEPROP 0 LASTPIN (-3175 775) $PN AR75
J 2
(-3135 785);
DISPLAY 0.489362 (-3135 785);
PAINT MONO (-3135 785);
FORCEPROP 0 LASTPIN (-3175 725) $PN AT3
J 2
(-3135 735);
DISPLAY 0.489362 (-3135 735);
PAINT MONO (-3135 735);
FORCEPROP 0 LASTPIN (-3175 675) $PN AT4
J 2
(-3135 685);
DISPLAY 0.489362 (-3135 685);
PAINT MONO (-3135 685);
FORCEPROP 0 LASTPIN (-3175 625) $PN AT5
J 2
(-3135 635);
DISPLAY 0.489362 (-3135 635);
PAINT MONO (-3135 635);
FORCEPROP 0 LASTPIN (-3175 575) $PN AT6
J 2
(-3135 585);
DISPLAY 0.489362 (-3135 585);
PAINT MONO (-3135 585);
FORCEPROP 0 LASTPIN (-3175 525) $PN AT8
J 2
(-3135 535);
DISPLAY 0.489362 (-3135 535);
PAINT MONO (-3135 535);
FORCEPROP 0 LASTPIN (-2075 6425) $PN AT9
J 0
(-2065 6435);
DISPLAY 0.489362 (-2065 6435);
PAINT MONO (-2065 6435);
FORCEPROP 0 LASTPIN (-2075 6375) $PN AT10
J 0
(-2065 6385);
DISPLAY 0.489362 (-2065 6385);
PAINT MONO (-2065 6385);
FORCEPROP 0 LASTPIN (-2075 6325) $PN AT12
J 0
(-2065 6335);
DISPLAY 0.489362 (-2065 6335);
PAINT MONO (-2065 6335);
FORCEPROP 0 LASTPIN (-2075 6275) $PN AT13
J 0
(-2065 6285);
DISPLAY 0.489362 (-2065 6285);
PAINT MONO (-2065 6285);
FORCEPROP 0 LASTPIN (-2075 6225) $PN AT15
J 0
(-2065 6235);
DISPLAY 0.489362 (-2065 6235);
PAINT MONO (-2065 6235);
FORCEPROP 0 LASTPIN (-2075 6175) $PN AT16
J 0
(-2065 6185);
DISPLAY 0.489362 (-2065 6185);
PAINT MONO (-2065 6185);
FORCEPROP 0 LASTPIN (-2075 6125) $PN AT17
J 0
(-2065 6135);
DISPLAY 0.489362 (-2065 6135);
PAINT MONO (-2065 6135);
FORCEPROP 0 LASTPIN (-2075 6075) $PN AT19
J 0
(-2065 6085);
DISPLAY 0.489362 (-2065 6085);
PAINT MONO (-2065 6085);
FORCEPROP 0 LASTPIN (-2075 6025) $PN AT20
J 0
(-2065 6035);
DISPLAY 0.489362 (-2065 6035);
PAINT MONO (-2065 6035);
FORCEPROP 0 LASTPIN (-2075 5975) $PN AT23
J 0
(-2065 5985);
DISPLAY 0.489362 (-2065 5985);
PAINT MONO (-2065 5985);
FORCEPROP 0 LASTPIN (-2075 5925) $PN AT25
J 0
(-2065 5935);
DISPLAY 0.489362 (-2065 5935);
PAINT MONO (-2065 5935);
FORCEPROP 0 LASTPIN (-2075 5875) $PN AT27
J 0
(-2065 5885);
DISPLAY 0.489362 (-2065 5885);
PAINT MONO (-2065 5885);
FORCEPROP 0 LASTPIN (-2075 5825) $PN AT29
J 0
(-2065 5835);
DISPLAY 0.489362 (-2065 5835);
PAINT MONO (-2065 5835);
FORCEPROP 0 LASTPIN (-2075 5775) $PN AT31
J 0
(-2065 5785);
DISPLAY 0.489362 (-2065 5785);
PAINT MONO (-2065 5785);
FORCEPROP 0 LASTPIN (-2075 5725) $PN AT33
J 0
(-2065 5735);
DISPLAY 0.489362 (-2065 5735);
PAINT MONO (-2065 5735);
FORCEPROP 0 LASTPIN (-2075 5675) $PN AT35
J 0
(-2065 5685);
DISPLAY 0.489362 (-2065 5685);
PAINT MONO (-2065 5685);
FORCEPROP 0 LASTPIN (-2075 5625) $PN AT37
J 0
(-2065 5635);
DISPLAY 0.489362 (-2065 5635);
PAINT MONO (-2065 5635);
FORCEPROP 0 LASTPIN (-2075 5575) $PN AT40
J 0
(-2065 5585);
DISPLAY 0.489362 (-2065 5585);
PAINT MONO (-2065 5585);
FORCEPROP 0 LASTPIN (-2075 5525) $PN AT42
J 0
(-2065 5535);
DISPLAY 0.489362 (-2065 5535);
PAINT MONO (-2065 5535);
FORCEPROP 0 LASTPIN (-2075 5475) $PN AT44
J 0
(-2065 5485);
DISPLAY 0.489362 (-2065 5485);
PAINT MONO (-2065 5485);
FORCEPROP 0 LASTPIN (-2075 5425) $PN AT46
J 0
(-2065 5435);
DISPLAY 0.489362 (-2065 5435);
PAINT MONO (-2065 5435);
FORCEPROP 0 LASTPIN (-2075 5375) $PN AT48
J 0
(-2065 5385);
DISPLAY 0.489362 (-2065 5385);
PAINT MONO (-2065 5385);
FORCEPROP 0 LASTPIN (-2075 5325) $PN AT50
J 0
(-2065 5335);
DISPLAY 0.489362 (-2065 5335);
PAINT MONO (-2065 5335);
FORCEPROP 0 LASTPIN (-2075 5275) $PN AT52
J 0
(-2065 5285);
DISPLAY 0.489362 (-2065 5285);
PAINT MONO (-2065 5285);
FORCEPROP 0 LASTPIN (-2075 5225) $PN AT54
J 0
(-2065 5235);
DISPLAY 0.489362 (-2065 5235);
PAINT MONO (-2065 5235);
FORCEPROP 0 LASTPIN (-2075 5175) $PN AT56
J 0
(-2065 5185);
DISPLAY 0.489362 (-2065 5185);
PAINT MONO (-2065 5185);
FORCEPROP 0 LASTPIN (-2075 5125) $PN AT57
J 0
(-2065 5135);
DISPLAY 0.489362 (-2065 5135);
PAINT MONO (-2065 5135);
FORCEPROP 0 LASTPIN (-2075 5075) $PN AT59
J 0
(-2065 5085);
DISPLAY 0.489362 (-2065 5085);
PAINT MONO (-2065 5085);
FORCEPROP 0 LASTPIN (-2075 5025) $PN AT60
J 0
(-2065 5035);
DISPLAY 0.489362 (-2065 5035);
PAINT MONO (-2065 5035);
FORCEPROP 0 LASTPIN (-2075 4975) $PN AT61
J 0
(-2065 4985);
DISPLAY 0.489362 (-2065 4985);
PAINT MONO (-2065 4985);
FORCEPROP 0 LASTPIN (-2075 4925) $PN AT63
J 0
(-2065 4935);
DISPLAY 0.489362 (-2065 4935);
PAINT MONO (-2065 4935);
FORCEPROP 0 LASTPIN (-2075 4875) $PN AT64
J 0
(-2065 4885);
DISPLAY 0.489362 (-2065 4885);
PAINT MONO (-2065 4885);
FORCEPROP 0 LASTPIN (-2075 4825) $PN AT66
J 0
(-2065 4835);
DISPLAY 0.489362 (-2065 4835);
PAINT MONO (-2065 4835);
FORCEPROP 0 LASTPIN (-2075 4775) $PN AT67
J 0
(-2065 4785);
DISPLAY 0.489362 (-2065 4785);
PAINT MONO (-2065 4785);
FORCEPROP 0 LASTPIN (-2075 4725) $PN AT68
J 0
(-2065 4735);
DISPLAY 0.489362 (-2065 4735);
PAINT MONO (-2065 4735);
FORCEPROP 0 LASTPIN (-2075 4675) $PN AT70
J 0
(-2065 4685);
DISPLAY 0.489362 (-2065 4685);
PAINT MONO (-2065 4685);
FORCEPROP 0 LASTPIN (-2075 4625) $PN AT71
J 0
(-2065 4635);
DISPLAY 0.489362 (-2065 4635);
PAINT MONO (-2065 4635);
FORCEPROP 0 LASTPIN (-2075 4575) $PN AT72
J 0
(-2065 4585);
DISPLAY 0.489362 (-2065 4585);
PAINT MONO (-2065 4585);
FORCEPROP 0 LASTPIN (-2075 4525) $PN AT73
J 0
(-2065 4535);
DISPLAY 0.489362 (-2065 4535);
PAINT MONO (-2065 4535);
FORCEPROP 0 LASTPIN (-2075 4475) $PN AU1
J 0
(-2065 4485);
DISPLAY 0.489362 (-2065 4485);
PAINT MONO (-2065 4485);
FORCEPROP 0 LASTPIN (-2075 4425) $PN AU3
J 0
(-2065 4435);
DISPLAY 0.489362 (-2065 4435);
PAINT MONO (-2065 4435);
FORCEPROP 0 LASTPIN (-2075 4375) $PN AU4
J 0
(-2065 4385);
DISPLAY 0.489362 (-2065 4385);
PAINT MONO (-2065 4385);
FORCEPROP 0 LASTPIN (-2075 4325) $PN AU6
J 0
(-2065 4335);
DISPLAY 0.489362 (-2065 4335);
PAINT MONO (-2065 4335);
FORCEPROP 0 LASTPIN (-2075 4275) $PN AU8
J 0
(-2065 4285);
DISPLAY 0.489362 (-2065 4285);
PAINT MONO (-2065 4285);
FORCEPROP 0 LASTPIN (-2075 4225) $PN AU11
J 0
(-2065 4235);
DISPLAY 0.489362 (-2065 4235);
PAINT MONO (-2065 4235);
FORCEPROP 0 LASTPIN (-2075 4175) $PN AU13
J 0
(-2065 4185);
DISPLAY 0.489362 (-2065 4185);
PAINT MONO (-2065 4185);
FORCEPROP 0 LASTPIN (-2075 4125) $PN AU15
J 0
(-2065 4135);
DISPLAY 0.489362 (-2065 4135);
PAINT MONO (-2065 4135);
FORCEPROP 0 LASTPIN (-2075 4075) $PN AU18
J 0
(-2065 4085);
DISPLAY 0.489362 (-2065 4085);
PAINT MONO (-2065 4085);
FORCEPROP 0 LASTPIN (-2075 4025) $PN AU20
J 0
(-2065 4035);
DISPLAY 0.489362 (-2065 4035);
PAINT MONO (-2065 4035);
FORCEPROP 0 LASTPIN (-2075 3975) $PN AU22
J 0
(-2065 3985);
DISPLAY 0.489362 (-2065 3985);
PAINT MONO (-2065 3985);
FORCEPROP 0 LASTPIN (-2075 3925) $PN AU24
J 0
(-2065 3935);
DISPLAY 0.489362 (-2065 3935);
PAINT MONO (-2065 3935);
FORCEPROP 0 LASTPIN (-2075 3875) $PN AU26
J 0
(-2065 3885);
DISPLAY 0.489362 (-2065 3885);
PAINT MONO (-2065 3885);
FORCEPROP 0 LASTPIN (-2075 3825) $PN AU28
J 0
(-2065 3835);
DISPLAY 0.489362 (-2065 3835);
PAINT MONO (-2065 3835);
FORCEPROP 0 LASTPIN (-2075 3775) $PN AU30
J 0
(-2065 3785);
DISPLAY 0.489362 (-2065 3785);
PAINT MONO (-2065 3785);
FORCEPROP 0 LASTPIN (-2075 3725) $PN AU32
J 0
(-2065 3735);
DISPLAY 0.489362 (-2065 3735);
PAINT MONO (-2065 3735);
FORCEPROP 0 LASTPIN (-2075 3675) $PN AU34
J 0
(-2065 3685);
DISPLAY 0.489362 (-2065 3685);
PAINT MONO (-2065 3685);
FORCEPROP 0 LASTPIN (-2075 3625) $PN AU36
J 0
(-2065 3635);
DISPLAY 0.489362 (-2065 3635);
PAINT MONO (-2065 3635);
FORCEPROP 0 LASTPIN (-2075 3575) $PN AU41
J 0
(-2065 3585);
DISPLAY 0.489362 (-2065 3585);
PAINT MONO (-2065 3585);
FORCEPROP 0 LASTPIN (-2075 3525) $PN AU43
J 0
(-2065 3535);
DISPLAY 0.489362 (-2065 3535);
PAINT MONO (-2065 3535);
FORCEPROP 0 LASTPIN (-2075 3475) $PN AU45
J 0
(-2065 3485);
DISPLAY 0.489362 (-2065 3485);
PAINT MONO (-2065 3485);
FORCEPROP 0 LASTPIN (-2075 3425) $PN AU47
J 0
(-2065 3435);
DISPLAY 0.489362 (-2065 3435);
PAINT MONO (-2065 3435);
FORCEPROP 0 LASTPIN (-2075 3375) $PN AU49
J 0
(-2065 3385);
DISPLAY 0.489362 (-2065 3385);
PAINT MONO (-2065 3385);
FORCEPROP 0 LASTPIN (-2075 3325) $PN AU51
J 0
(-2065 3335);
DISPLAY 0.489362 (-2065 3335);
PAINT MONO (-2065 3335);
FORCEPROP 0 LASTPIN (-2075 3275) $PN AU53
J 0
(-2065 3285);
DISPLAY 0.489362 (-2065 3285);
PAINT MONO (-2065 3285);
FORCEPROP 0 LASTPIN (-2075 3225) $PN AU56
J 0
(-2065 3235);
DISPLAY 0.489362 (-2065 3235);
PAINT MONO (-2065 3235);
FORCEPROP 0 LASTPIN (-2075 3175) $PN AU58
J 0
(-2065 3185);
DISPLAY 0.489362 (-2065 3185);
PAINT MONO (-2065 3185);
FORCEPROP 0 LASTPIN (-2075 3125) $PN AU61
J 0
(-2065 3135);
DISPLAY 0.489362 (-2065 3135);
PAINT MONO (-2065 3135);
FORCEPROP 0 LASTPIN (-2075 3075) $PN AU63
J 0
(-2065 3085);
DISPLAY 0.489362 (-2065 3085);
PAINT MONO (-2065 3085);
FORCEPROP 0 LASTPIN (-2075 3025) $PN AU65
J 0
(-2065 3035);
DISPLAY 0.489362 (-2065 3035);
PAINT MONO (-2065 3035);
FORCEPROP 0 LASTPIN (-2075 2975) $PN AU68
J 0
(-2065 2985);
DISPLAY 0.489362 (-2065 2985);
PAINT MONO (-2065 2985);
FORCEPROP 0 LASTPIN (-2075 2925) $PN AU70
J 0
(-2065 2935);
DISPLAY 0.489362 (-2065 2935);
PAINT MONO (-2065 2935);
FORCEPROP 0 LASTPIN (-2075 2875) $PN AU72
J 0
(-2065 2885);
DISPLAY 0.489362 (-2065 2885);
PAINT MONO (-2065 2885);
FORCEPROP 0 LASTPIN (-2075 2825) $PN AU73
J 0
(-2065 2835);
DISPLAY 0.489362 (-2065 2835);
PAINT MONO (-2065 2835);
FORCEPROP 0 LASTPIN (-2075 2775) $PN AU75
J 0
(-2065 2785);
DISPLAY 0.489362 (-2065 2785);
PAINT MONO (-2065 2785);
FORCEPROP 0 LASTPIN (-2075 2725) $PN AV3
J 0
(-2065 2735);
DISPLAY 0.489362 (-2065 2735);
PAINT MONO (-2065 2735);
FORCEPROP 0 LASTPIN (-2075 2675) $PN AV8
J 0
(-2065 2685);
DISPLAY 0.489362 (-2065 2685);
PAINT MONO (-2065 2685);
FORCEPROP 0 LASTPIN (-2075 2625) $PN AV10
J 0
(-2065 2635);
DISPLAY 0.489362 (-2065 2635);
PAINT MONO (-2065 2635);
FORCEPROP 0 LASTPIN (-2075 2575) $PN AV15
J 0
(-2065 2585);
DISPLAY 0.489362 (-2065 2585);
PAINT MONO (-2065 2585);
FORCEPROP 0 LASTPIN (-2075 2525) $PN AV17
J 0
(-2065 2535);
DISPLAY 0.489362 (-2065 2535);
PAINT MONO (-2065 2535);
FORCEPROP 0 LASTPIN (-2075 2475) $PN AV23
J 0
(-2065 2485);
DISPLAY 0.489362 (-2065 2485);
PAINT MONO (-2065 2485);
FORCEPROP 0 LASTPIN (-2075 2425) $PN AV25
J 0
(-2065 2435);
DISPLAY 0.489362 (-2065 2435);
PAINT MONO (-2065 2435);
FORCEPROP 0 LASTPIN (-2075 2375) $PN AV27
J 0
(-2065 2385);
DISPLAY 0.489362 (-2065 2385);
PAINT MONO (-2065 2385);
FORCEPROP 0 LASTPIN (-2075 2325) $PN AV29
J 0
(-2065 2335);
DISPLAY 0.489362 (-2065 2335);
PAINT MONO (-2065 2335);
FORCEPROP 0 LASTPIN (-2075 2275) $PN AV31
J 0
(-2065 2285);
DISPLAY 0.489362 (-2065 2285);
PAINT MONO (-2065 2285);
FORCEPROP 0 LASTPIN (-2075 2225) $PN AV33
J 0
(-2065 2235);
DISPLAY 0.489362 (-2065 2235);
PAINT MONO (-2065 2235);
FORCEPROP 0 LASTPIN (-2075 2175) $PN AV35
J 0
(-2065 2185);
DISPLAY 0.489362 (-2065 2185);
PAINT MONO (-2065 2185);
FORCEPROP 0 LASTPIN (-2075 2125) $PN AV37
J 0
(-2065 2135);
DISPLAY 0.489362 (-2065 2135);
PAINT MONO (-2065 2135);
FORCEPROP 0 LASTPIN (-2075 2075) $PN AV40
J 0
(-2065 2085);
DISPLAY 0.489362 (-2065 2085);
PAINT MONO (-2065 2085);
FORCEPROP 0 LASTPIN (-2075 2025) $PN AV42
J 0
(-2065 2035);
DISPLAY 0.489362 (-2065 2035);
PAINT MONO (-2065 2035);
FORCEPROP 0 LASTPIN (-2075 1975) $PN AV44
J 0
(-2065 1985);
DISPLAY 0.489362 (-2065 1985);
PAINT MONO (-2065 1985);
FORCEPROP 0 LASTPIN (-2075 1925) $PN AV46
J 0
(-2065 1935);
DISPLAY 0.489362 (-2065 1935);
PAINT MONO (-2065 1935);
FORCEPROP 0 LASTPIN (-2075 1875) $PN AV48
J 0
(-2065 1885);
DISPLAY 0.489362 (-2065 1885);
PAINT MONO (-2065 1885);
FORCEPROP 0 LASTPIN (-2075 1825) $PN AV50
J 0
(-2065 1835);
DISPLAY 0.489362 (-2065 1835);
PAINT MONO (-2065 1835);
FORCEPROP 0 LASTPIN (-2075 1775) $PN AV52
J 0
(-2065 1785);
DISPLAY 0.489362 (-2065 1785);
PAINT MONO (-2065 1785);
FORCEPROP 0 LASTPIN (-2075 1725) $PN AV54
J 0
(-2065 1735);
DISPLAY 0.489362 (-2065 1735);
PAINT MONO (-2065 1735);
FORCEPROP 0 LASTPIN (-2075 1675) $PN AV59
J 0
(-2065 1685);
DISPLAY 0.489362 (-2065 1685);
PAINT MONO (-2065 1685);
FORCEPROP 0 LASTPIN (-2075 1625) $PN AV61
J 0
(-2065 1635);
DISPLAY 0.489362 (-2065 1635);
PAINT MONO (-2065 1635);
FORCEPROP 0 LASTPIN (-2075 1575) $PN AV66
J 0
(-2065 1585);
DISPLAY 0.489362 (-2065 1585);
PAINT MONO (-2065 1585);
FORCEPROP 0 LASTPIN (-2075 1525) $PN AV68
J 0
(-2065 1535);
DISPLAY 0.489362 (-2065 1535);
PAINT MONO (-2065 1535);
FORCEPROP 0 LASTPIN (-2075 1475) $PN AV73
J 0
(-2065 1485);
DISPLAY 0.489362 (-2065 1485);
PAINT MONO (-2065 1485);
FORCEPROP 0 LASTPIN (-2075 1425) $PN AW1
J 0
(-2065 1435);
DISPLAY 0.489362 (-2065 1435);
PAINT MONO (-2065 1435);
FORCEPROP 0 LASTPIN (-2075 1375) $PN AW4
J 0
(-2065 1385);
DISPLAY 0.489362 (-2065 1385);
PAINT MONO (-2065 1385);
FORCEPROP 0 LASTPIN (-2075 1325) $PN AW6
J 0
(-2065 1335);
DISPLAY 0.489362 (-2065 1335);
PAINT MONO (-2065 1335);
FORCEPROP 0 LASTPIN (-2075 1275) $PN AW8
J 0
(-2065 1285);
DISPLAY 0.489362 (-2065 1285);
PAINT MONO (-2065 1285);
FORCEPROP 0 LASTPIN (-2075 1225) $PN AW11
J 0
(-2065 1235);
DISPLAY 0.489362 (-2065 1235);
PAINT MONO (-2065 1235);
FORCEPROP 0 LASTPIN (-2075 1175) $PN AW13
J 0
(-2065 1185);
DISPLAY 0.489362 (-2065 1185);
PAINT MONO (-2065 1185);
FORCEPROP 0 LASTPIN (-2075 1125) $PN AW15
J 0
(-2065 1135);
DISPLAY 0.489362 (-2065 1135);
PAINT MONO (-2065 1135);
FORCEPROP 0 LASTPIN (-2075 1075) $PN AW18
J 0
(-2065 1085);
DISPLAY 0.489362 (-2065 1085);
PAINT MONO (-2065 1085);
FORCEPROP 0 LASTPIN (-2075 1025) $PN AW20
J 0
(-2065 1035);
DISPLAY 0.489362 (-2065 1035);
PAINT MONO (-2065 1035);
FORCEPROP 0 LASTPIN (-2075 975) $PN AW22
J 0
(-2065 985);
DISPLAY 0.489362 (-2065 985);
PAINT MONO (-2065 985);
FORCEPROP 0 LASTPIN (-2075 925) $PN AW24
J 0
(-2065 935);
DISPLAY 0.489362 (-2065 935);
PAINT MONO (-2065 935);
FORCEPROP 0 LASTPIN (-2075 875) $PN AW26
J 0
(-2065 885);
DISPLAY 0.489362 (-2065 885);
PAINT MONO (-2065 885);
FORCEPROP 0 LASTPIN (-2075 825) $PN AW28
J 0
(-2065 835);
DISPLAY 0.489362 (-2065 835);
PAINT MONO (-2065 835);
FORCEPROP 0 LASTPIN (-2075 775) $PN AW49
J 0
(-2065 785);
DISPLAY 0.489362 (-2065 785);
PAINT MONO (-2065 785);
FORCEPROP 0 LASTPIN (-2075 725) $PN AW51
J 0
(-2065 735);
DISPLAY 0.489362 (-2065 735);
PAINT MONO (-2065 735);
FORCEPROP 0 LASTPIN (-2075 675) $PN AW53
J 0
(-2065 685);
DISPLAY 0.489362 (-2065 685);
PAINT MONO (-2065 685);
FORCEPROP 0 LASTPIN (-2075 625) $PN AW56
J 0
(-2065 635);
DISPLAY 0.489362 (-2065 635);
PAINT MONO (-2065 635);
FORCEPROP 0 LASTPIN (-2075 575) $PN AW58
J 0
(-2065 585);
DISPLAY 0.489362 (-2065 585);
PAINT MONO (-2065 585);
FORCEPROP 0 LASTPIN (-2075 525) $PN AW61
J 0
(-2065 535);
DISPLAY 0.489362 (-2065 535);
PAINT MONO (-2065 535);
FORCEPROP 2 LAST PART_TYPE SMLF
J 0
(-3025 6700);
DISPLAY 1.021277 (-3025 6700);
FORCEPROP 1 LAST MATERIAL IO
J 0
(-3020 6557);
DISPLAY 0.489362 (-3020 6557);
PAINT SKYBLUE (-3020 6557);
FORCEPROP 2 LAST VALUE SOCKET6096_13568-001
J 0
(-2900 6550);
DISPLAY 0.489362 (-2900 6550);
PAINT SKYBLUE (-2900 6550);
FORCEPROP 1 LAST NEEDS_NO_SIZE TRUE
J 0
(-2625 3475);
DISPLAY 0.723404 (-2625 3475);
PAINT GREEN (-2625 3475);
DISPLAY INVISIBLE (-2625 3475);
FORCEPROP 1 LAST CDS_LMAN_SYM_OUTLINE -400,3050,400,-3050
J 0
(-2625 3475);
DISPLAY 0.468085 (-2625 3475);
PAINT GREEN (-2625 3475);
DISPLAY INVISIBLE (-2625 3475);
FORCEPROP 2 LAST CDS_LIB pure_quanta
J 0
(-2625 3475);
DISPLAY INVISIBLE (-2625 3475);
FORCEPROP 1 LAST PATH I23
J 0
(-2625 3475);
DISPLAY 0.723404 (-2625 3475);
PAINT GREEN (-2625 3475);
DISPLAY INVISIBLE (-2625 3475);
FORCEPROP 1 LAST PART_NUMBER DGA^6000030
J 0
(-3020 6650);
DISPLAY 0.489362 (-3020 6650);
PAINT SKYBLUE (-3020 6650);
DISPLAY INVISIBLE (-3020 6650);
FORCEADD GENOA_SP5..33
(-1000 3475);
FORCEPROP 1 LAST LOCATION U25
J 0
(-1395 6600);
DISPLAY 0.489362 (-1395 6600);
PAINT SKYBLUE (-1395 6600);
FORCEPROP 0 LAST $SEC 33
J 0
(-1375 6875);
DISPLAY 0.680851 (-1375 6875);
PAINT MONO (-1375 6875);
DISPLAY INVISIBLE (-1375 6875);
FORCEPROP 0 LAST CDS_SEC 33
J 0
(-1575 6700);
DISPLAY 1.021277 (-1575 6700);
DISPLAY INVISIBLE (-1575 6700);
FORCEPROP 0 LASTPIN (-1550 6425) $PN AW63
J 2
(-1510 6435);
DISPLAY 0.489362 (-1510 6435);
PAINT MONO (-1510 6435);
FORCEPROP 0 LASTPIN (-1550 6375) $PN AW65
J 2
(-1510 6385);
DISPLAY 0.489362 (-1510 6385);
PAINT MONO (-1510 6385);
FORCEPROP 0 LASTPIN (-1550 6325) $PN AW68
J 2
(-1510 6335);
DISPLAY 0.489362 (-1510 6335);
PAINT MONO (-1510 6335);
FORCEPROP 0 LASTPIN (-1550 6275) $PN AW70
J 2
(-1510 6285);
DISPLAY 0.489362 (-1510 6285);
PAINT MONO (-1510 6285);
FORCEPROP 0 LASTPIN (-1550 6225) $PN AW72
J 2
(-1510 6235);
DISPLAY 0.489362 (-1510 6235);
PAINT MONO (-1510 6235);
FORCEPROP 0 LASTPIN (-1550 6175) $PN AW75
J 2
(-1510 6185);
DISPLAY 0.489362 (-1510 6185);
PAINT MONO (-1510 6185);
FORCEPROP 0 LASTPIN (-1550 6125) $PN AY3
J 2
(-1510 6135);
DISPLAY 0.489362 (-1510 6135);
PAINT MONO (-1510 6135);
FORCEPROP 0 LASTPIN (-1550 6075) $PN AY5
J 2
(-1510 6085);
DISPLAY 0.489362 (-1510 6085);
PAINT MONO (-1510 6085);
FORCEPROP 0 LASTPIN (-1550 6025) $PN AY8
J 2
(-1510 6035);
DISPLAY 0.489362 (-1510 6035);
PAINT MONO (-1510 6035);
FORCEPROP 0 LASTPIN (-1550 5975) $PN AY10
J 2
(-1510 5985);
DISPLAY 0.489362 (-1510 5985);
PAINT MONO (-1510 5985);
FORCEPROP 0 LASTPIN (-1550 5925) $PN AY12
J 2
(-1510 5935);
DISPLAY 0.489362 (-1510 5935);
PAINT MONO (-1510 5935);
FORCEPROP 0 LASTPIN (-1550 5875) $PN AY15
J 2
(-1510 5885);
DISPLAY 0.489362 (-1510 5885);
PAINT MONO (-1510 5885);
FORCEPROP 0 LASTPIN (-1550 5825) $PN AY17
J 2
(-1510 5835);
DISPLAY 0.489362 (-1510 5835);
PAINT MONO (-1510 5835);
FORCEPROP 0 LASTPIN (-1550 5775) $PN AY19
J 2
(-1510 5785);
DISPLAY 0.489362 (-1510 5785);
PAINT MONO (-1510 5785);
FORCEPROP 0 LASTPIN (-1550 5725) $PN AY23
J 2
(-1510 5735);
DISPLAY 0.489362 (-1510 5735);
PAINT MONO (-1510 5735);
FORCEPROP 0 LASTPIN (-1550 5675) $PN AY25
J 2
(-1510 5685);
DISPLAY 0.489362 (-1510 5685);
PAINT MONO (-1510 5685);
FORCEPROP 0 LASTPIN (-1550 5625) $PN AY27
J 2
(-1510 5635);
DISPLAY 0.489362 (-1510 5635);
PAINT MONO (-1510 5635);
FORCEPROP 0 LASTPIN (-1550 5575) $PN AY48
J 2
(-1510 5585);
DISPLAY 0.489362 (-1510 5585);
PAINT MONO (-1510 5585);
FORCEPROP 0 LASTPIN (-1550 5525) $PN AY50
J 2
(-1510 5535);
DISPLAY 0.489362 (-1510 5535);
PAINT MONO (-1510 5535);
FORCEPROP 0 LASTPIN (-1550 5475) $PN AY52
J 2
(-1510 5485);
DISPLAY 0.489362 (-1510 5485);
PAINT MONO (-1510 5485);
FORCEPROP 0 LASTPIN (-1550 5425) $PN AY54
J 2
(-1510 5435);
DISPLAY 0.489362 (-1510 5435);
PAINT MONO (-1510 5435);
FORCEPROP 0 LASTPIN (-1550 5375) $PN AY57
J 2
(-1510 5385);
DISPLAY 0.489362 (-1510 5385);
PAINT MONO (-1510 5385);
FORCEPROP 0 LASTPIN (-1550 5325) $PN AY59
J 2
(-1510 5335);
DISPLAY 0.489362 (-1510 5335);
PAINT MONO (-1510 5335);
FORCEPROP 0 LASTPIN (-1550 5275) $PN AY61
J 2
(-1510 5285);
DISPLAY 0.489362 (-1510 5285);
PAINT MONO (-1510 5285);
FORCEPROP 0 LASTPIN (-1550 5225) $PN AY64
J 2
(-1510 5235);
DISPLAY 0.489362 (-1510 5235);
PAINT MONO (-1510 5235);
FORCEPROP 0 LASTPIN (-1550 5175) $PN AY66
J 2
(-1510 5185);
DISPLAY 0.489362 (-1510 5185);
PAINT MONO (-1510 5185);
FORCEPROP 0 LASTPIN (-1550 5125) $PN AY68
J 2
(-1510 5135);
DISPLAY 0.489362 (-1510 5135);
PAINT MONO (-1510 5135);
FORCEPROP 0 LASTPIN (-1550 5075) $PN AY71
J 2
(-1510 5085);
DISPLAY 0.489362 (-1510 5085);
PAINT MONO (-1510 5085);
FORCEPROP 0 LASTPIN (-1550 5025) $PN AY73
J 2
(-1510 5035);
DISPLAY 0.489362 (-1510 5035);
PAINT MONO (-1510 5035);
FORCEPROP 0 LASTPIN (-1550 4975) $PN BA1
J 2
(-1510 4985);
DISPLAY 0.489362 (-1510 4985);
PAINT MONO (-1510 4985);
FORCEPROP 0 LASTPIN (-1550 4925) $PN BA6
J 2
(-1510 4935);
DISPLAY 0.489362 (-1510 4935);
PAINT MONO (-1510 4935);
FORCEPROP 0 LASTPIN (-1550 4875) $PN BA8
J 2
(-1510 4885);
DISPLAY 0.489362 (-1510 4885);
PAINT MONO (-1510 4885);
FORCEPROP 0 LASTPIN (-1550 4825) $PN BA13
J 2
(-1510 4835);
DISPLAY 0.489362 (-1510 4835);
PAINT MONO (-1510 4835);
FORCEPROP 0 LASTPIN (-1550 4775) $PN BA15
J 2
(-1510 4785);
DISPLAY 0.489362 (-1510 4785);
PAINT MONO (-1510 4785);
FORCEPROP 0 LASTPIN (-1550 4725) $PN BA20
J 2
(-1510 4735);
DISPLAY 0.489362 (-1510 4735);
PAINT MONO (-1510 4735);
FORCEPROP 0 LASTPIN (-1550 4675) $PN BA22
J 2
(-1510 4685);
DISPLAY 0.489362 (-1510 4685);
PAINT MONO (-1510 4685);
FORCEPROP 0 LASTPIN (-1550 4625) $PN BA24
J 2
(-1510 4635);
DISPLAY 0.489362 (-1510 4635);
PAINT MONO (-1510 4635);
FORCEPROP 0 LASTPIN (-1550 4575) $PN BA26
J 2
(-1510 4585);
DISPLAY 0.489362 (-1510 4585);
PAINT MONO (-1510 4585);
FORCEPROP 0 LASTPIN (-1550 4525) $PN BA28
J 2
(-1510 4535);
DISPLAY 0.489362 (-1510 4535);
PAINT MONO (-1510 4535);
FORCEPROP 0 LASTPIN (-1550 4475) $PN BA49
J 2
(-1510 4485);
DISPLAY 0.489362 (-1510 4485);
PAINT MONO (-1510 4485);
FORCEPROP 0 LASTPIN (-1550 4425) $PN BA51
J 2
(-1510 4435);
DISPLAY 0.489362 (-1510 4435);
PAINT MONO (-1510 4435);
FORCEPROP 0 LASTPIN (-1550 4375) $PN BA53
J 2
(-1510 4385);
DISPLAY 0.489362 (-1510 4385);
PAINT MONO (-1510 4385);
FORCEPROP 0 LASTPIN (-1550 4325) $PN BA56
J 2
(-1510 4335);
DISPLAY 0.489362 (-1510 4335);
PAINT MONO (-1510 4335);
FORCEPROP 0 LASTPIN (-1550 4275) $PN BA61
J 2
(-1510 4285);
DISPLAY 0.489362 (-1510 4285);
PAINT MONO (-1510 4285);
FORCEPROP 0 LASTPIN (-1550 4225) $PN BA63
J 2
(-1510 4235);
DISPLAY 0.489362 (-1510 4235);
PAINT MONO (-1510 4235);
FORCEPROP 0 LASTPIN (-1550 4175) $PN BA68
J 2
(-1510 4185);
DISPLAY 0.489362 (-1510 4185);
PAINT MONO (-1510 4185);
FORCEPROP 0 LASTPIN (-1550 4125) $PN BA70
J 2
(-1510 4135);
DISPLAY 0.489362 (-1510 4135);
PAINT MONO (-1510 4135);
FORCEPROP 0 LASTPIN (-1550 4075) $PN BA75
J 2
(-1510 4085);
DISPLAY 0.489362 (-1510 4085);
PAINT MONO (-1510 4085);
FORCEPROP 0 LASTPIN (-1550 4025) $PN BB3
J 2
(-1510 4035);
DISPLAY 0.489362 (-1510 4035);
PAINT MONO (-1510 4035);
FORCEPROP 0 LASTPIN (-1550 3975) $PN BB5
J 2
(-1510 3985);
DISPLAY 0.489362 (-1510 3985);
PAINT MONO (-1510 3985);
FORCEPROP 0 LASTPIN (-1550 3925) $PN BB8
J 2
(-1510 3935);
DISPLAY 0.489362 (-1510 3935);
PAINT MONO (-1510 3935);
FORCEPROP 0 LASTPIN (-1550 3875) $PN BB10
J 2
(-1510 3885);
DISPLAY 0.489362 (-1510 3885);
PAINT MONO (-1510 3885);
FORCEPROP 0 LASTPIN (-1550 3825) $PN BB12
J 2
(-1510 3835);
DISPLAY 0.489362 (-1510 3835);
PAINT MONO (-1510 3835);
FORCEPROP 0 LASTPIN (-1550 3775) $PN BB15
J 2
(-1510 3785);
DISPLAY 0.489362 (-1510 3785);
PAINT MONO (-1510 3785);
FORCEPROP 0 LASTPIN (-1550 3725) $PN BB17
J 2
(-1510 3735);
DISPLAY 0.489362 (-1510 3735);
PAINT MONO (-1510 3735);
FORCEPROP 0 LASTPIN (-1550 3675) $PN BB19
J 2
(-1510 3685);
DISPLAY 0.489362 (-1510 3685);
PAINT MONO (-1510 3685);
FORCEPROP 0 LASTPIN (-1550 3625) $PN BB23
J 2
(-1510 3635);
DISPLAY 0.489362 (-1510 3635);
PAINT MONO (-1510 3635);
FORCEPROP 0 LASTPIN (-1550 3575) $PN BB25
J 2
(-1510 3585);
DISPLAY 0.489362 (-1510 3585);
PAINT MONO (-1510 3585);
FORCEPROP 0 LASTPIN (-1550 3525) $PN BB27
J 2
(-1510 3535);
DISPLAY 0.489362 (-1510 3535);
PAINT MONO (-1510 3535);
FORCEPROP 0 LASTPIN (-1550 3475) $PN BB48
J 2
(-1510 3485);
DISPLAY 0.489362 (-1510 3485);
PAINT MONO (-1510 3485);
FORCEPROP 0 LASTPIN (-1550 3425) $PN BB50
J 2
(-1510 3435);
DISPLAY 0.489362 (-1510 3435);
PAINT MONO (-1510 3435);
FORCEPROP 0 LASTPIN (-1550 3375) $PN BB52
J 2
(-1510 3385);
DISPLAY 0.489362 (-1510 3385);
PAINT MONO (-1510 3385);
FORCEPROP 0 LASTPIN (-1550 3325) $PN BB54
J 2
(-1510 3335);
DISPLAY 0.489362 (-1510 3335);
PAINT MONO (-1510 3335);
FORCEPROP 0 LASTPIN (-1550 3275) $PN BB57
J 2
(-1510 3285);
DISPLAY 0.489362 (-1510 3285);
PAINT MONO (-1510 3285);
FORCEPROP 0 LASTPIN (-1550 3225) $PN BB59
J 2
(-1510 3235);
DISPLAY 0.489362 (-1510 3235);
PAINT MONO (-1510 3235);
FORCEPROP 0 LASTPIN (-1550 3175) $PN BB61
J 2
(-1510 3185);
DISPLAY 0.489362 (-1510 3185);
PAINT MONO (-1510 3185);
FORCEPROP 0 LASTPIN (-1550 3125) $PN BB64
J 2
(-1510 3135);
DISPLAY 0.489362 (-1510 3135);
PAINT MONO (-1510 3135);
FORCEPROP 0 LASTPIN (-1550 3075) $PN BB66
J 2
(-1510 3085);
DISPLAY 0.489362 (-1510 3085);
PAINT MONO (-1510 3085);
FORCEPROP 0 LASTPIN (-1550 3025) $PN BB68
J 2
(-1510 3035);
DISPLAY 0.489362 (-1510 3035);
PAINT MONO (-1510 3035);
FORCEPROP 0 LASTPIN (-1550 2975) $PN BB71
J 2
(-1510 2985);
DISPLAY 0.489362 (-1510 2985);
PAINT MONO (-1510 2985);
FORCEPROP 0 LASTPIN (-1550 2925) $PN BB73
J 2
(-1510 2935);
DISPLAY 0.489362 (-1510 2935);
PAINT MONO (-1510 2935);
FORCEPROP 0 LASTPIN (-1550 2875) $PN BC1
J 2
(-1510 2885);
DISPLAY 0.489362 (-1510 2885);
PAINT MONO (-1510 2885);
FORCEPROP 0 LASTPIN (-1550 2825) $PN BC4
J 2
(-1510 2835);
DISPLAY 0.489362 (-1510 2835);
PAINT MONO (-1510 2835);
FORCEPROP 0 LASTPIN (-1550 2775) $PN BC6
J 2
(-1510 2785);
DISPLAY 0.489362 (-1510 2785);
PAINT MONO (-1510 2785);
FORCEPROP 0 LASTPIN (-1550 2725) $PN BC8
J 2
(-1510 2735);
DISPLAY 0.489362 (-1510 2735);
PAINT MONO (-1510 2735);
FORCEPROP 0 LASTPIN (-1550 2675) $PN BC11
J 2
(-1510 2685);
DISPLAY 0.489362 (-1510 2685);
PAINT MONO (-1510 2685);
FORCEPROP 0 LASTPIN (-1550 2625) $PN BC13
J 2
(-1510 2635);
DISPLAY 0.489362 (-1510 2635);
PAINT MONO (-1510 2635);
FORCEPROP 0 LASTPIN (-1550 2575) $PN BC15
J 2
(-1510 2585);
DISPLAY 0.489362 (-1510 2585);
PAINT MONO (-1510 2585);
FORCEPROP 0 LASTPIN (-1550 2525) $PN BC18
J 2
(-1510 2535);
DISPLAY 0.489362 (-1510 2535);
PAINT MONO (-1510 2535);
FORCEPROP 0 LASTPIN (-1550 2475) $PN BC20
J 2
(-1510 2485);
DISPLAY 0.489362 (-1510 2485);
PAINT MONO (-1510 2485);
FORCEPROP 0 LASTPIN (-1550 2425) $PN BC22
J 2
(-1510 2435);
DISPLAY 0.489362 (-1510 2435);
PAINT MONO (-1510 2435);
FORCEPROP 0 LASTPIN (-1550 2375) $PN BC24
J 2
(-1510 2385);
DISPLAY 0.489362 (-1510 2385);
PAINT MONO (-1510 2385);
FORCEPROP 0 LASTPIN (-1550 2325) $PN BC26
J 2
(-1510 2335);
DISPLAY 0.489362 (-1510 2335);
PAINT MONO (-1510 2335);
FORCEPROP 0 LASTPIN (-1550 2275) $PN BC28
J 2
(-1510 2285);
DISPLAY 0.489362 (-1510 2285);
PAINT MONO (-1510 2285);
FORCEPROP 0 LASTPIN (-1550 2225) $PN BC49
J 2
(-1510 2235);
DISPLAY 0.489362 (-1510 2235);
PAINT MONO (-1510 2235);
FORCEPROP 0 LASTPIN (-1550 2175) $PN BC50
J 2
(-1510 2185);
DISPLAY 0.489362 (-1510 2185);
PAINT MONO (-1510 2185);
FORCEPROP 0 LASTPIN (-1550 2125) $PN BC51
J 2
(-1510 2135);
DISPLAY 0.489362 (-1510 2135);
PAINT MONO (-1510 2135);
FORCEPROP 0 LASTPIN (-1550 2075) $PN BC53
J 2
(-1510 2085);
DISPLAY 0.489362 (-1510 2085);
PAINT MONO (-1510 2085);
FORCEPROP 0 LASTPIN (-1550 2025) $PN BC56
J 2
(-1510 2035);
DISPLAY 0.489362 (-1510 2035);
PAINT MONO (-1510 2035);
FORCEPROP 0 LASTPIN (-1550 1975) $PN BC58
J 2
(-1510 1985);
DISPLAY 0.489362 (-1510 1985);
PAINT MONO (-1510 1985);
FORCEPROP 0 LASTPIN (-1550 1925) $PN BC61
J 2
(-1510 1935);
DISPLAY 0.489362 (-1510 1935);
PAINT MONO (-1510 1935);
FORCEPROP 0 LASTPIN (-1550 1875) $PN BC63
J 2
(-1510 1885);
DISPLAY 0.489362 (-1510 1885);
PAINT MONO (-1510 1885);
FORCEPROP 0 LASTPIN (-1550 1825) $PN BC65
J 2
(-1510 1835);
DISPLAY 0.489362 (-1510 1835);
PAINT MONO (-1510 1835);
FORCEPROP 0 LASTPIN (-1550 1775) $PN BC68
J 2
(-1510 1785);
DISPLAY 0.489362 (-1510 1785);
PAINT MONO (-1510 1785);
FORCEPROP 0 LASTPIN (-1550 1725) $PN BC70
J 2
(-1510 1735);
DISPLAY 0.489362 (-1510 1735);
PAINT MONO (-1510 1735);
FORCEPROP 0 LASTPIN (-1550 1675) $PN BC72
J 2
(-1510 1685);
DISPLAY 0.489362 (-1510 1685);
PAINT MONO (-1510 1685);
FORCEPROP 0 LASTPIN (-1550 1625) $PN BC75
J 2
(-1510 1635);
DISPLAY 0.489362 (-1510 1635);
PAINT MONO (-1510 1635);
FORCEPROP 0 LASTPIN (-1550 1575) $PN BD3
J 2
(-1510 1585);
DISPLAY 0.489362 (-1510 1585);
PAINT MONO (-1510 1585);
FORCEPROP 0 LASTPIN (-1550 1525) $PN BD8
J 2
(-1510 1535);
DISPLAY 0.489362 (-1510 1535);
PAINT MONO (-1510 1535);
FORCEPROP 0 LASTPIN (-1550 1475) $PN BD10
J 2
(-1510 1485);
DISPLAY 0.489362 (-1510 1485);
PAINT MONO (-1510 1485);
FORCEPROP 0 LASTPIN (-1550 1425) $PN BD15
J 2
(-1510 1435);
DISPLAY 0.489362 (-1510 1435);
PAINT MONO (-1510 1435);
FORCEPROP 0 LASTPIN (-1550 1375) $PN BD17
J 2
(-1510 1385);
DISPLAY 0.489362 (-1510 1385);
PAINT MONO (-1510 1385);
FORCEPROP 0 LASTPIN (-1550 1325) $PN BD23
J 2
(-1510 1335);
DISPLAY 0.489362 (-1510 1335);
PAINT MONO (-1510 1335);
FORCEPROP 0 LASTPIN (-1550 1275) $PN BD25
J 2
(-1510 1285);
DISPLAY 0.489362 (-1510 1285);
PAINT MONO (-1510 1285);
FORCEPROP 0 LASTPIN (-1550 1225) $PN BD27
J 2
(-1510 1235);
DISPLAY 0.489362 (-1510 1235);
PAINT MONO (-1510 1235);
FORCEPROP 0 LASTPIN (-1550 1175) $PN BD49
J 2
(-1510 1185);
DISPLAY 0.489362 (-1510 1185);
PAINT MONO (-1510 1185);
FORCEPROP 0 LASTPIN (-1550 1125) $PN BD51
J 2
(-1510 1135);
DISPLAY 0.489362 (-1510 1135);
PAINT MONO (-1510 1135);
FORCEPROP 0 LASTPIN (-1550 1075) $PN BD53
J 2
(-1510 1085);
DISPLAY 0.489362 (-1510 1085);
PAINT MONO (-1510 1085);
FORCEPROP 0 LASTPIN (-1550 1025) $PN BD57
J 2
(-1510 1035);
DISPLAY 0.489362 (-1510 1035);
PAINT MONO (-1510 1035);
FORCEPROP 0 LASTPIN (-1550 975) $PN BD59
J 2
(-1510 985);
DISPLAY 0.489362 (-1510 985);
PAINT MONO (-1510 985);
FORCEPROP 0 LASTPIN (-1550 925) $PN BD61
J 2
(-1510 935);
DISPLAY 0.489362 (-1510 935);
PAINT MONO (-1510 935);
FORCEPROP 0 LASTPIN (-1550 875) $PN BD64
J 2
(-1510 885);
DISPLAY 0.489362 (-1510 885);
PAINT MONO (-1510 885);
FORCEPROP 0 LASTPIN (-1550 825) $PN BD66
J 2
(-1510 835);
DISPLAY 0.489362 (-1510 835);
PAINT MONO (-1510 835);
FORCEPROP 0 LASTPIN (-1550 775) $PN BD68
J 2
(-1510 785);
DISPLAY 0.489362 (-1510 785);
PAINT MONO (-1510 785);
FORCEPROP 0 LASTPIN (-1550 725) $PN BD71
J 2
(-1510 735);
DISPLAY 0.489362 (-1510 735);
PAINT MONO (-1510 735);
FORCEPROP 0 LASTPIN (-1550 675) $PN BD73
J 2
(-1510 685);
DISPLAY 0.489362 (-1510 685);
PAINT MONO (-1510 685);
FORCEPROP 0 LASTPIN (-1550 625) $PN BF3
J 2
(-1510 635);
DISPLAY 0.489362 (-1510 635);
PAINT MONO (-1510 635);
FORCEPROP 0 LASTPIN (-1550 575) $PN BF5
J 2
(-1510 585);
DISPLAY 0.489362 (-1510 585);
PAINT MONO (-1510 585);
FORCEPROP 0 LASTPIN (-1550 525) $PN BF8
J 2
(-1510 535);
DISPLAY 0.489362 (-1510 535);
PAINT MONO (-1510 535);
FORCEPROP 0 LASTPIN (-450 6425) $PN BF10
J 0
(-440 6435);
DISPLAY 0.489362 (-440 6435);
PAINT MONO (-440 6435);
FORCEPROP 0 LASTPIN (-450 6375) $PN BF12
J 0
(-440 6385);
DISPLAY 0.489362 (-440 6385);
PAINT MONO (-440 6385);
FORCEPROP 0 LASTPIN (-450 6325) $PN BF15
J 0
(-440 6335);
DISPLAY 0.489362 (-440 6335);
PAINT MONO (-440 6335);
FORCEPROP 0 LASTPIN (-450 6275) $PN BF17
J 0
(-440 6285);
DISPLAY 0.489362 (-440 6285);
PAINT MONO (-440 6285);
FORCEPROP 0 LASTPIN (-450 6225) $PN BF19
J 0
(-440 6235);
DISPLAY 0.489362 (-440 6235);
PAINT MONO (-440 6235);
FORCEPROP 0 LASTPIN (-450 6175) $PN BF22
J 0
(-440 6185);
DISPLAY 0.489362 (-440 6185);
PAINT MONO (-440 6185);
FORCEPROP 0 LASTPIN (-450 6125) $PN BF24
J 0
(-440 6135);
DISPLAY 0.489362 (-440 6135);
PAINT MONO (-440 6135);
FORCEPROP 0 LASTPIN (-450 6075) $PN BF26
J 0
(-440 6085);
DISPLAY 0.489362 (-440 6085);
PAINT MONO (-440 6085);
FORCEPROP 0 LASTPIN (-450 6025) $PN BF28
J 0
(-440 6035);
DISPLAY 0.489362 (-440 6035);
PAINT MONO (-440 6035);
FORCEPROP 0 LASTPIN (-450 5975) $PN BF49
J 0
(-440 5985);
DISPLAY 0.489362 (-440 5985);
PAINT MONO (-440 5985);
FORCEPROP 0 LASTPIN (-450 5925) $PN BF50
J 0
(-440 5935);
DISPLAY 0.489362 (-440 5935);
PAINT MONO (-440 5935);
FORCEPROP 0 LASTPIN (-450 5875) $PN BF52
J 0
(-440 5885);
DISPLAY 0.489362 (-440 5885);
PAINT MONO (-440 5885);
FORCEPROP 0 LASTPIN (-450 5825) $PN BF54
J 0
(-440 5835);
DISPLAY 0.489362 (-440 5835);
PAINT MONO (-440 5835);
FORCEPROP 0 LASTPIN (-450 5775) $PN BF59
J 0
(-440 5785);
DISPLAY 0.489362 (-440 5785);
PAINT MONO (-440 5785);
FORCEPROP 0 LASTPIN (-450 5725) $PN BF61
J 0
(-440 5735);
DISPLAY 0.489362 (-440 5735);
PAINT MONO (-440 5735);
FORCEPROP 0 LASTPIN (-450 5675) $PN BF66
J 0
(-440 5685);
DISPLAY 0.489362 (-440 5685);
PAINT MONO (-440 5685);
FORCEPROP 0 LASTPIN (-450 5625) $PN BF68
J 0
(-440 5635);
DISPLAY 0.489362 (-440 5635);
PAINT MONO (-440 5635);
FORCEPROP 0 LASTPIN (-450 5575) $PN BF73
J 0
(-440 5585);
DISPLAY 0.489362 (-440 5585);
PAINT MONO (-440 5585);
FORCEPROP 0 LASTPIN (-450 5525) $PN BG1
J 0
(-440 5535);
DISPLAY 0.489362 (-440 5535);
PAINT MONO (-440 5535);
FORCEPROP 0 LASTPIN (-450 5475) $PN BG4
J 0
(-440 5485);
DISPLAY 0.489362 (-440 5485);
PAINT MONO (-440 5485);
FORCEPROP 0 LASTPIN (-450 5425) $PN BG6
J 0
(-440 5435);
DISPLAY 0.489362 (-440 5435);
PAINT MONO (-440 5435);
FORCEPROP 0 LASTPIN (-450 5375) $PN BG8
J 0
(-440 5385);
DISPLAY 0.489362 (-440 5385);
PAINT MONO (-440 5385);
FORCEPROP 0 LASTPIN (-450 5325) $PN BG11
J 0
(-440 5335);
DISPLAY 0.489362 (-440 5335);
PAINT MONO (-440 5335);
FORCEPROP 0 LASTPIN (-450 5275) $PN BG13
J 0
(-440 5285);
DISPLAY 0.489362 (-440 5285);
PAINT MONO (-440 5285);
FORCEPROP 0 LASTPIN (-450 5225) $PN BG15
J 0
(-440 5235);
DISPLAY 0.489362 (-440 5235);
PAINT MONO (-440 5235);
FORCEPROP 0 LASTPIN (-450 5175) $PN BG18
J 0
(-440 5185);
DISPLAY 0.489362 (-440 5185);
PAINT MONO (-440 5185);
FORCEPROP 0 LASTPIN (-450 5125) $PN BG20
J 0
(-440 5135);
DISPLAY 0.489362 (-440 5135);
PAINT MONO (-440 5135);
FORCEPROP 0 LASTPIN (-450 5075) $PN BG23
J 0
(-440 5085);
DISPLAY 0.489362 (-440 5085);
PAINT MONO (-440 5085);
FORCEPROP 0 LASTPIN (-450 5025) $PN BG25
J 0
(-440 5035);
DISPLAY 0.489362 (-440 5035);
PAINT MONO (-440 5035);
FORCEPROP 0 LASTPIN (-450 4975) $PN BG27
J 0
(-440 4985);
DISPLAY 0.489362 (-440 4985);
PAINT MONO (-440 4985);
FORCEPROP 0 LASTPIN (-450 4925) $PN BG49
J 0
(-440 4935);
DISPLAY 0.489362 (-440 4935);
PAINT MONO (-440 4935);
FORCEPROP 0 LASTPIN (-450 4875) $PN BG51
J 0
(-440 4885);
DISPLAY 0.489362 (-440 4885);
PAINT MONO (-440 4885);
FORCEPROP 0 LASTPIN (-450 4825) $PN BG53
J 0
(-440 4835);
DISPLAY 0.489362 (-440 4835);
PAINT MONO (-440 4835);
FORCEPROP 0 LASTPIN (-450 4775) $PN BG56
J 0
(-440 4785);
DISPLAY 0.489362 (-440 4785);
PAINT MONO (-440 4785);
FORCEPROP 0 LASTPIN (-450 4725) $PN BG58
J 0
(-440 4735);
DISPLAY 0.489362 (-440 4735);
PAINT MONO (-440 4735);
FORCEPROP 0 LASTPIN (-450 4675) $PN BG61
J 0
(-440 4685);
DISPLAY 0.489362 (-440 4685);
PAINT MONO (-440 4685);
FORCEPROP 0 LASTPIN (-450 4625) $PN BG63
J 0
(-440 4635);
DISPLAY 0.489362 (-440 4635);
PAINT MONO (-440 4635);
FORCEPROP 0 LASTPIN (-450 4575) $PN BG65
J 0
(-440 4585);
DISPLAY 0.489362 (-440 4585);
PAINT MONO (-440 4585);
FORCEPROP 0 LASTPIN (-450 4525) $PN BG68
J 0
(-440 4535);
DISPLAY 0.489362 (-440 4535);
PAINT MONO (-440 4535);
FORCEPROP 0 LASTPIN (-450 4475) $PN BG70
J 0
(-440 4485);
DISPLAY 0.489362 (-440 4485);
PAINT MONO (-440 4485);
FORCEPROP 0 LASTPIN (-450 4425) $PN BG72
J 0
(-440 4435);
DISPLAY 0.489362 (-440 4435);
PAINT MONO (-440 4435);
FORCEPROP 0 LASTPIN (-450 4375) $PN BG75
J 0
(-440 4385);
DISPLAY 0.489362 (-440 4385);
PAINT MONO (-440 4385);
FORCEPROP 0 LASTPIN (-450 4325) $PN BH3
J 0
(-440 4335);
DISPLAY 0.489362 (-440 4335);
PAINT MONO (-440 4335);
FORCEPROP 0 LASTPIN (-450 4275) $PN BH5
J 0
(-440 4285);
DISPLAY 0.489362 (-440 4285);
PAINT MONO (-440 4285);
FORCEPROP 0 LASTPIN (-450 4225) $PN BH8
J 0
(-440 4235);
DISPLAY 0.489362 (-440 4235);
PAINT MONO (-440 4235);
FORCEPROP 0 LASTPIN (-450 4175) $PN BH10
J 0
(-440 4185);
DISPLAY 0.489362 (-440 4185);
PAINT MONO (-440 4185);
FORCEPROP 0 LASTPIN (-450 4125) $PN BH12
J 0
(-440 4135);
DISPLAY 0.489362 (-440 4135);
PAINT MONO (-440 4135);
FORCEPROP 0 LASTPIN (-450 4075) $PN BH15
J 0
(-440 4085);
DISPLAY 0.489362 (-440 4085);
PAINT MONO (-440 4085);
FORCEPROP 0 LASTPIN (-450 4025) $PN BH17
J 0
(-440 4035);
DISPLAY 0.489362 (-440 4035);
PAINT MONO (-440 4035);
FORCEPROP 0 LASTPIN (-450 3975) $PN BH19
J 0
(-440 3985);
DISPLAY 0.489362 (-440 3985);
PAINT MONO (-440 3985);
FORCEPROP 0 LASTPIN (-450 3925) $PN BH22
J 0
(-440 3935);
DISPLAY 0.489362 (-440 3935);
PAINT MONO (-440 3935);
FORCEPROP 0 LASTPIN (-450 3875) $PN BH24
J 0
(-440 3885);
DISPLAY 0.489362 (-440 3885);
PAINT MONO (-440 3885);
FORCEPROP 0 LASTPIN (-450 3825) $PN BH26
J 0
(-440 3835);
DISPLAY 0.489362 (-440 3835);
PAINT MONO (-440 3835);
FORCEPROP 0 LASTPIN (-450 3775) $PN BH28
J 0
(-440 3785);
DISPLAY 0.489362 (-440 3785);
PAINT MONO (-440 3785);
FORCEPROP 0 LASTPIN (-450 3725) $PN BH49
J 0
(-440 3735);
DISPLAY 0.489362 (-440 3735);
PAINT MONO (-440 3735);
FORCEPROP 0 LASTPIN (-450 3675) $PN BH50
J 0
(-440 3685);
DISPLAY 0.489362 (-440 3685);
PAINT MONO (-440 3685);
FORCEPROP 0 LASTPIN (-450 3625) $PN BH52
J 0
(-440 3635);
DISPLAY 0.489362 (-440 3635);
PAINT MONO (-440 3635);
FORCEPROP 0 LASTPIN (-450 3575) $PN BH54
J 0
(-440 3585);
DISPLAY 0.489362 (-440 3585);
PAINT MONO (-440 3585);
FORCEPROP 0 LASTPIN (-450 3525) $PN BH57
J 0
(-440 3535);
DISPLAY 0.489362 (-440 3535);
PAINT MONO (-440 3535);
FORCEPROP 0 LASTPIN (-450 3475) $PN BH59
J 0
(-440 3485);
DISPLAY 0.489362 (-440 3485);
PAINT MONO (-440 3485);
FORCEPROP 0 LASTPIN (-450 3425) $PN BH61
J 0
(-440 3435);
DISPLAY 0.489362 (-440 3435);
PAINT MONO (-440 3435);
FORCEPROP 0 LASTPIN (-450 3375) $PN BH64
J 0
(-440 3385);
DISPLAY 0.489362 (-440 3385);
PAINT MONO (-440 3385);
FORCEPROP 0 LASTPIN (-450 3325) $PN BH66
J 0
(-440 3335);
DISPLAY 0.489362 (-440 3335);
PAINT MONO (-440 3335);
FORCEPROP 0 LASTPIN (-450 3275) $PN BH68
J 0
(-440 3285);
DISPLAY 0.489362 (-440 3285);
PAINT MONO (-440 3285);
FORCEPROP 0 LASTPIN (-450 3225) $PN BH71
J 0
(-440 3235);
DISPLAY 0.489362 (-440 3235);
PAINT MONO (-440 3235);
FORCEPROP 0 LASTPIN (-450 3175) $PN BH73
J 0
(-440 3185);
DISPLAY 0.489362 (-440 3185);
PAINT MONO (-440 3185);
FORCEPROP 0 LASTPIN (-450 3125) $PN BJ1
J 0
(-440 3135);
DISPLAY 0.489362 (-440 3135);
PAINT MONO (-440 3135);
FORCEPROP 0 LASTPIN (-450 3075) $PN BJ6
J 0
(-440 3085);
DISPLAY 0.489362 (-440 3085);
PAINT MONO (-440 3085);
FORCEPROP 0 LASTPIN (-450 3025) $PN BJ8
J 0
(-440 3035);
DISPLAY 0.489362 (-440 3035);
PAINT MONO (-440 3035);
FORCEPROP 0 LASTPIN (-450 2975) $PN BJ13
J 0
(-440 2985);
DISPLAY 0.489362 (-440 2985);
PAINT MONO (-440 2985);
FORCEPROP 0 LASTPIN (-450 2925) $PN BJ15
J 0
(-440 2935);
DISPLAY 0.489362 (-440 2935);
PAINT MONO (-440 2935);
FORCEPROP 0 LASTPIN (-450 2875) $PN BJ20
J 0
(-440 2885);
DISPLAY 0.489362 (-440 2885);
PAINT MONO (-440 2885);
FORCEPROP 0 LASTPIN (-450 2825) $PN BJ22
J 0
(-440 2835);
DISPLAY 0.489362 (-440 2835);
PAINT MONO (-440 2835);
FORCEPROP 0 LASTPIN (-450 2775) $PN BJ24
J 0
(-440 2785);
DISPLAY 0.489362 (-440 2785);
PAINT MONO (-440 2785);
FORCEPROP 0 LASTPIN (-450 2725) $PN BJ26
J 0
(-440 2735);
DISPLAY 0.489362 (-440 2735);
PAINT MONO (-440 2735);
FORCEPROP 0 LASTPIN (-450 2675) $PN BJ28
J 0
(-440 2685);
DISPLAY 0.489362 (-440 2685);
PAINT MONO (-440 2685);
FORCEPROP 0 LASTPIN (-450 2625) $PN BJ49
J 0
(-440 2635);
DISPLAY 0.489362 (-440 2635);
PAINT MONO (-440 2635);
FORCEPROP 0 LASTPIN (-450 2575) $PN BJ51
J 0
(-440 2585);
DISPLAY 0.489362 (-440 2585);
PAINT MONO (-440 2585);
FORCEPROP 0 LASTPIN (-450 2525) $PN BJ53
J 0
(-440 2535);
DISPLAY 0.489362 (-440 2535);
PAINT MONO (-440 2535);
FORCEPROP 0 LASTPIN (-450 2475) $PN BJ56
J 0
(-440 2485);
DISPLAY 0.489362 (-440 2485);
PAINT MONO (-440 2485);
FORCEPROP 0 LASTPIN (-450 2425) $PN BJ61
J 0
(-440 2435);
DISPLAY 0.489362 (-440 2435);
PAINT MONO (-440 2435);
FORCEPROP 0 LASTPIN (-450 2375) $PN BJ63
J 0
(-440 2385);
DISPLAY 0.489362 (-440 2385);
PAINT MONO (-440 2385);
FORCEPROP 0 LASTPIN (-450 2325) $PN BJ68
J 0
(-440 2335);
DISPLAY 0.489362 (-440 2335);
PAINT MONO (-440 2335);
FORCEPROP 0 LASTPIN (-450 2275) $PN BJ70
J 0
(-440 2285);
DISPLAY 0.489362 (-440 2285);
PAINT MONO (-440 2285);
FORCEPROP 0 LASTPIN (-450 2225) $PN BJ75
J 0
(-440 2235);
DISPLAY 0.489362 (-440 2235);
PAINT MONO (-440 2235);
FORCEPROP 0 LASTPIN (-450 2175) $PN BK3
J 0
(-440 2185);
DISPLAY 0.489362 (-440 2185);
PAINT MONO (-440 2185);
FORCEPROP 0 LASTPIN (-450 2125) $PN BK5
J 0
(-440 2135);
DISPLAY 0.489362 (-440 2135);
PAINT MONO (-440 2135);
FORCEPROP 0 LASTPIN (-450 2075) $PN BK8
J 0
(-440 2085);
DISPLAY 0.489362 (-440 2085);
PAINT MONO (-440 2085);
FORCEPROP 0 LASTPIN (-450 2025) $PN BK10
J 0
(-440 2035);
DISPLAY 0.489362 (-440 2035);
PAINT MONO (-440 2035);
FORCEPROP 0 LASTPIN (-450 1975) $PN BK12
J 0
(-440 1985);
DISPLAY 0.489362 (-440 1985);
PAINT MONO (-440 1985);
FORCEPROP 0 LASTPIN (-450 1925) $PN BK15
J 0
(-440 1935);
DISPLAY 0.489362 (-440 1935);
PAINT MONO (-440 1935);
FORCEPROP 0 LASTPIN (-450 1875) $PN BK17
J 0
(-440 1885);
DISPLAY 0.489362 (-440 1885);
PAINT MONO (-440 1885);
FORCEPROP 0 LASTPIN (-450 1825) $PN BK19
J 0
(-440 1835);
DISPLAY 0.489362 (-440 1835);
PAINT MONO (-440 1835);
FORCEPROP 0 LASTPIN (-450 1775) $PN BK23
J 0
(-440 1785);
DISPLAY 0.489362 (-440 1785);
PAINT MONO (-440 1785);
FORCEPROP 0 LASTPIN (-450 1725) $PN BK25
J 0
(-440 1735);
DISPLAY 0.489362 (-440 1735);
PAINT MONO (-440 1735);
FORCEPROP 0 LASTPIN (-450 1675) $PN BK27
J 0
(-440 1685);
DISPLAY 0.489362 (-440 1685);
PAINT MONO (-440 1685);
FORCEPROP 0 LASTPIN (-450 1625) $PN BK48
J 0
(-440 1635);
DISPLAY 0.489362 (-440 1635);
PAINT MONO (-440 1635);
FORCEPROP 0 LASTPIN (-450 1575) $PN BK50
J 0
(-440 1585);
DISPLAY 0.489362 (-440 1585);
PAINT MONO (-440 1585);
FORCEPROP 0 LASTPIN (-450 1525) $PN BK52
J 0
(-440 1535);
DISPLAY 0.489362 (-440 1535);
PAINT MONO (-440 1535);
FORCEPROP 0 LASTPIN (-450 1475) $PN BK54
J 0
(-440 1485);
DISPLAY 0.489362 (-440 1485);
PAINT MONO (-440 1485);
FORCEPROP 0 LASTPIN (-450 1425) $PN BK57
J 0
(-440 1435);
DISPLAY 0.489362 (-440 1435);
PAINT MONO (-440 1435);
FORCEPROP 0 LASTPIN (-450 1375) $PN BK59
J 0
(-440 1385);
DISPLAY 0.489362 (-440 1385);
PAINT MONO (-440 1385);
FORCEPROP 0 LASTPIN (-450 1325) $PN BK61
J 0
(-440 1335);
DISPLAY 0.489362 (-440 1335);
PAINT MONO (-440 1335);
FORCEPROP 0 LASTPIN (-450 1275) $PN BK64
J 0
(-440 1285);
DISPLAY 0.489362 (-440 1285);
PAINT MONO (-440 1285);
FORCEPROP 0 LASTPIN (-450 1225) $PN BK66
J 0
(-440 1235);
DISPLAY 0.489362 (-440 1235);
PAINT MONO (-440 1235);
FORCEPROP 0 LASTPIN (-450 1175) $PN BK68
J 0
(-440 1185);
DISPLAY 0.489362 (-440 1185);
PAINT MONO (-440 1185);
FORCEPROP 0 LASTPIN (-450 1125) $PN BK71
J 0
(-440 1135);
DISPLAY 0.489362 (-440 1135);
PAINT MONO (-440 1135);
FORCEPROP 0 LASTPIN (-450 1075) $PN BK73
J 0
(-440 1085);
DISPLAY 0.489362 (-440 1085);
PAINT MONO (-440 1085);
FORCEPROP 0 LASTPIN (-450 1025) $PN BL1
J 0
(-440 1035);
DISPLAY 0.489362 (-440 1035);
PAINT MONO (-440 1035);
FORCEPROP 0 LASTPIN (-450 975) $PN BL4
J 0
(-440 985);
DISPLAY 0.489362 (-440 985);
PAINT MONO (-440 985);
FORCEPROP 0 LASTPIN (-450 925) $PN BL6
J 0
(-440 935);
DISPLAY 0.489362 (-440 935);
PAINT MONO (-440 935);
FORCEPROP 0 LASTPIN (-450 875) $PN BL8
J 0
(-440 885);
DISPLAY 0.489362 (-440 885);
PAINT MONO (-440 885);
FORCEPROP 0 LASTPIN (-450 825) $PN BL11
J 0
(-440 835);
DISPLAY 0.489362 (-440 835);
PAINT MONO (-440 835);
FORCEPROP 0 LASTPIN (-450 775) $PN BL13
J 0
(-440 785);
DISPLAY 0.489362 (-440 785);
PAINT MONO (-440 785);
FORCEPROP 0 LASTPIN (-450 725) $PN BL15
J 0
(-440 735);
DISPLAY 0.489362 (-440 735);
PAINT MONO (-440 735);
FORCEPROP 0 LASTPIN (-450 675) $PN BL18
J 0
(-440 685);
DISPLAY 0.489362 (-440 685);
PAINT MONO (-440 685);
FORCEPROP 0 LASTPIN (-450 625) $PN BL20
J 0
(-440 635);
DISPLAY 0.489362 (-440 635);
PAINT MONO (-440 635);
FORCEPROP 0 LASTPIN (-450 575) $PN BL22
J 0
(-440 585);
DISPLAY 0.489362 (-440 585);
PAINT MONO (-440 585);
FORCEPROP 0 LASTPIN (-450 525) $PN BL24
J 0
(-440 535);
DISPLAY 0.489362 (-440 535);
PAINT MONO (-440 535);
FORCEPROP 2 LAST PART_TYPE SMLF
J 0
(-1400 6700);
DISPLAY 1.021277 (-1400 6700);
FORCEPROP 1 LAST MATERIAL IO
J 0
(-1395 6557);
DISPLAY 0.489362 (-1395 6557);
PAINT SKYBLUE (-1395 6557);
FORCEPROP 2 LAST VALUE SOCKET6096_13568-001
J 0
(-1275 6550);
DISPLAY 0.489362 (-1275 6550);
PAINT SKYBLUE (-1275 6550);
FORCEPROP 1 LAST NEEDS_NO_SIZE TRUE
J 0
(-1000 3475);
DISPLAY 0.723404 (-1000 3475);
PAINT GREEN (-1000 3475);
DISPLAY INVISIBLE (-1000 3475);
FORCEPROP 1 LAST CDS_LMAN_SYM_OUTLINE -400,3050,400,-3050
J 0
(-1000 3475);
DISPLAY 0.468085 (-1000 3475);
PAINT GREEN (-1000 3475);
DISPLAY INVISIBLE (-1000 3475);
FORCEPROP 2 LAST CDS_LIB pure_quanta
J 0
(-1000 3475);
DISPLAY INVISIBLE (-1000 3475);
FORCEPROP 1 LAST PATH I24
J 0
(-1000 3475);
DISPLAY 0.723404 (-1000 3475);
PAINT GREEN (-1000 3475);
DISPLAY INVISIBLE (-1000 3475);
FORCEPROP 1 LAST PART_NUMBER DGA^6000030
J 0
(-1395 6650);
DISPLAY 0.489362 (-1395 6650);
PAINT SKYBLUE (-1395 6650);
DISPLAY INVISIBLE (-1395 6650);
FORCEADD UNIVERSAL_GND..1
(-9275 350);
FORCEPROP 3 LASTPIN (-9275 400) SIG_NAME GND\g
J 0
(-9265 410);
DISPLAY 0.659574 (-9265 410);
PAINT MONO (-9265 410);
DISPLAY INVISIBLE (-9265 410);
FORCEPROP 2 LAST CDS_LIB pure_quanta_power
J 0
(-9275 350);
DISPLAY INVISIBLE (-9275 350);
FORCEPROP 1 LAST HDL_POWER GND
J 1
(-9250 275);
DISPLAY 0.872340 (-9250 275);
PAINT GREEN (-9250 275);
DISPLAY INVISIBLE (-9250 275);
FORCEPROP 1 LAST PATH I39
J 0
(-9200 350);
DISPLAY 0.872340 (-9200 350);
PAINT AQUA (-9200 350);
DISPLAY INVISIBLE (-9200 350);
FORCEADD UNIVERSAL_GND..1
(-7750 375);
FORCEPROP 3 LASTPIN (-7750 425) SIG_NAME GND\g
J 0
(-7740 435);
DISPLAY 0.659574 (-7740 435);
PAINT MONO (-7740 435);
DISPLAY INVISIBLE (-7740 435);
FORCEPROP 2 LAST CDS_LIB pure_quanta_power
J 0
(-7750 375);
DISPLAY INVISIBLE (-7750 375);
FORCEPROP 1 LAST HDL_POWER GND
J 1
(-7725 300);
DISPLAY 0.872340 (-7725 300);
PAINT GREEN (-7725 300);
DISPLAY INVISIBLE (-7725 300);
FORCEPROP 1 LAST PATH I40
J 0
(-7675 375);
DISPLAY 0.872340 (-7675 375);
PAINT AQUA (-7675 375);
DISPLAY INVISIBLE (-7675 375);
FORCEADD UNIVERSAL_GND..1
(-6275 400);
FORCEPROP 3 LASTPIN (-6275 450) SIG_NAME GND\g
J 0
(-6265 460);
DISPLAY 0.659574 (-6265 460);
PAINT MONO (-6265 460);
DISPLAY INVISIBLE (-6265 460);
FORCEPROP 2 LAST CDS_LIB pure_quanta_power
J 0
(-6275 400);
DISPLAY INVISIBLE (-6275 400);
FORCEPROP 1 LAST HDL_POWER GND
J 1
(-6250 325);
DISPLAY 0.872340 (-6250 325);
PAINT GREEN (-6250 325);
DISPLAY INVISIBLE (-6250 325);
FORCEPROP 1 LAST PATH I41
J 0
(-6200 400);
DISPLAY 0.872340 (-6200 400);
PAINT AQUA (-6200 400);
DISPLAY INVISIBLE (-6200 400);
FORCEADD UNIVERSAL_GND..1
(-3275 425);
FORCEPROP 3 LASTPIN (-3275 475) SIG_NAME GND\g
J 0
(-3265 485);
DISPLAY 0.659574 (-3265 485);
PAINT MONO (-3265 485);
DISPLAY INVISIBLE (-3265 485);
FORCEPROP 2 LAST CDS_LIB pure_quanta_power
J 0
(-3275 425);
DISPLAY INVISIBLE (-3275 425);
FORCEPROP 1 LAST HDL_POWER GND
J 1
(-3250 350);
DISPLAY 0.872340 (-3250 350);
PAINT GREEN (-3250 350);
DISPLAY INVISIBLE (-3250 350);
FORCEPROP 1 LAST PATH I43
J 0
(-3200 425);
DISPLAY 0.872340 (-3200 425);
PAINT AQUA (-3200 425);
DISPLAY INVISIBLE (-3200 425);
FORCEADD UNIVERSAL_GND..1
(-1650 450);
FORCEPROP 3 LASTPIN (-1650 500) SIG_NAME GND\g
J 0
(-1640 510);
DISPLAY 0.659574 (-1640 510);
PAINT MONO (-1640 510);
DISPLAY INVISIBLE (-1640 510);
FORCEPROP 2 LAST CDS_LIB pure_quanta_power
J 0
(-1650 450);
DISPLAY INVISIBLE (-1650 450);
FORCEPROP 1 LAST HDL_POWER GND
J 1
(-1625 375);
DISPLAY 0.872340 (-1625 375);
PAINT GREEN (-1625 375);
DISPLAY INVISIBLE (-1625 375);
FORCEPROP 1 LAST PATH I44
J 0
(-1575 450);
DISPLAY 0.872340 (-1575 450);
PAINT AQUA (-1575 450);
DISPLAY INVISIBLE (-1575 450);
FORCEADD UNIVERSAL_GND..1
(-7925 375);
FORCEPROP 3 LASTPIN (-7925 425) SIG_NAME GND\g
J 0
(-7915 435);
DISPLAY 0.659574 (-7915 435);
PAINT MONO (-7915 435);
DISPLAY INVISIBLE (-7915 435);
FORCEPROP 2 LAST CDS_LIB pure_quanta_power
J 0
(-7925 375);
DISPLAY INVISIBLE (-7925 375);
FORCEPROP 1 LAST HDL_POWER GND
J 1
(-7900 300);
DISPLAY 0.872340 (-7900 300);
PAINT GREEN (-7900 300);
DISPLAY INVISIBLE (-7900 300);
FORCEPROP 1 LAST PATH I45
J 0
(-7850 375);
DISPLAY 0.872340 (-7850 375);
PAINT AQUA (-7850 375);
DISPLAY INVISIBLE (-7850 375);
FORCEADD UNIVERSAL_GND..1
(-6400 400);
FORCEPROP 3 LASTPIN (-6400 450) SIG_NAME GND\g
J 0
(-6390 460);
DISPLAY 0.659574 (-6390 460);
PAINT MONO (-6390 460);
DISPLAY INVISIBLE (-6390 460);
FORCEPROP 2 LAST CDS_LIB pure_quanta_power
J 0
(-6400 400);
DISPLAY INVISIBLE (-6400 400);
FORCEPROP 1 LAST HDL_POWER GND
J 1
(-6375 325);
DISPLAY 0.872340 (-6375 325);
PAINT GREEN (-6375 325);
DISPLAY INVISIBLE (-6375 325);
FORCEPROP 1 LAST PATH I46
J 0
(-6325 400);
DISPLAY 0.872340 (-6325 400);
PAINT AQUA (-6325 400);
DISPLAY INVISIBLE (-6325 400);
FORCEADD UNIVERSAL_GND..1
(-4925 475);
FORCEPROP 3 LASTPIN (-4925 525) SIG_NAME GND\g
J 0
(-4915 535);
DISPLAY 0.659574 (-4915 535);
PAINT MONO (-4915 535);
DISPLAY INVISIBLE (-4915 535);
FORCEPROP 2 LAST CDS_LIB pure_quanta_power
J 0
(-4925 475);
DISPLAY INVISIBLE (-4925 475);
FORCEPROP 1 LAST HDL_POWER GND
J 1
(-4900 400);
DISPLAY 0.872340 (-4900 400);
PAINT GREEN (-4900 400);
DISPLAY INVISIBLE (-4900 400);
FORCEPROP 1 LAST PATH I47
J 0
(-4850 475);
DISPLAY 0.872340 (-4850 475);
PAINT AQUA (-4850 475);
DISPLAY INVISIBLE (-4850 475);
FORCEADD UNIVERSAL_GND..1
(-3425 500);
FORCEPROP 3 LASTPIN (-3425 550) SIG_NAME GND\g
J 0
(-3415 560);
DISPLAY 0.659574 (-3415 560);
PAINT MONO (-3415 560);
DISPLAY INVISIBLE (-3415 560);
FORCEPROP 2 LAST CDS_LIB pure_quanta_power
J 0
(-3425 500);
DISPLAY INVISIBLE (-3425 500);
FORCEPROP 1 LAST HDL_POWER GND
J 1
(-3400 425);
DISPLAY 0.872340 (-3400 425);
PAINT GREEN (-3400 425);
DISPLAY INVISIBLE (-3400 425);
FORCEPROP 1 LAST PATH I48
J 0
(-3350 500);
DISPLAY 0.872340 (-3350 500);
PAINT AQUA (-3350 500);
DISPLAY INVISIBLE (-3350 500);
FORCEADD UNIVERSAL_GND..1
(-1950 450);
FORCEPROP 3 LASTPIN (-1950 500) SIG_NAME GND\g
J 0
(-1940 510);
DISPLAY 0.659574 (-1940 510);
PAINT MONO (-1940 510);
DISPLAY INVISIBLE (-1940 510);
FORCEPROP 2 LAST CDS_LIB pure_quanta_power
J 0
(-1950 450);
DISPLAY INVISIBLE (-1950 450);
FORCEPROP 1 LAST HDL_POWER GND
J 1
(-1925 375);
DISPLAY 0.872340 (-1925 375);
PAINT GREEN (-1925 375);
DISPLAY INVISIBLE (-1925 375);
FORCEPROP 1 LAST PATH I49
J 0
(-1875 450);
DISPLAY 0.872340 (-1875 450);
PAINT AQUA (-1875 450);
DISPLAY INVISIBLE (-1875 450);
FORCEADD UNIVERSAL_GND..1
(-325 450);
FORCEPROP 3 LASTPIN (-325 500) SIG_NAME GND\g
J 0
(-315 510);
DISPLAY 0.659574 (-315 510);
PAINT MONO (-315 510);
DISPLAY INVISIBLE (-315 510);
FORCEPROP 2 LAST CDS_LIB pure_quanta_power
J 0
(-325 450);
DISPLAY INVISIBLE (-325 450);
FORCEPROP 1 LAST HDL_POWER GND
J 1
(-300 375);
DISPLAY 0.872340 (-300 375);
PAINT GREEN (-300 375);
DISPLAY INVISIBLE (-300 375);
FORCEPROP 1 LAST PATH I50
J 0
(-250 450);
DISPLAY 0.872340 (-250 450);
PAINT AQUA (-250 450);
DISPLAY INVISIBLE (-250 450);
FORCEADD UNIVERSAL_GND..1
(-4775 475);
FORCEPROP 3 LASTPIN (-4775 525) SIG_NAME GND\g
J 0
(-4765 535);
DISPLAY 0.659574 (-4765 535);
PAINT MONO (-4765 535);
DISPLAY INVISIBLE (-4765 535);
FORCEPROP 2 LAST CDS_LIB pure_quanta_power
J 0
(-4775 475);
DISPLAY INVISIBLE (-4775 475);
FORCEPROP 1 LAST HDL_POWER GND
J 1
(-4750 400);
DISPLAY 0.872340 (-4750 400);
PAINT GREEN (-4750 400);
DISPLAY INVISIBLE (-4750 400);
FORCEPROP 1 LAST PATH I51
J 0
(-4700 475);
DISPLAY 0.872340 (-4700 475);
PAINT AQUA (-4700 475);
DISPLAY INVISIBLE (-4700 475);
FORCEADD QUANTA_TITLE_BLOCK_C..1
(-100 100);
FORCEPROP 0 LAST CDS_CON_LAST_MODIFIED Thu Sep 14 16:11:54 2023
J 0
(-1985 115);
DISPLAY INVISIBLE (-1985 115);
FORCEPROP 1 LAST CUSTOM_TXT_CDS <CON_LAST_MODIFIED>
J 0
(-1985 115);
DISPLAY 0.978723 (-1985 115);
FORCEPROP 2 LAST CUSTOM_TXT_CDS <XR_PAGE_TITLE>
J 0
(-7990 5350);
DISPLAY 0.638298 (-7990 5350);
PAINT PINK (-7990 5350);
DISPLAY INVISIBLE (-7990 5350);
FORCEPROP 1 LAST CUSTOM_TXT_CDS <NAME_2>
J 0
(-3275 150);
FORCEPROP 1 LAST CUSTOM_TXT_CDS <NAME_1>
J 0
(-3275 275);
FORCEPROP 1 LAST CUSTOM_TXT_CDS <Q_NUMBER>
J 0
(-1503 203);
DISPLAY 1.212766 (-1503 203);
FORCEPROP 1 LAST CUSTOM_TXT_CDS <Q_PROJ>
J 0
(-2482 202);
DISPLAY 1.212766 (-2482 202);
FORCEPROP 1 LAST CUSTOM_TXT_CDS <Q_REV>
J 0
(-284 203);
DISPLAY 1.212766 (-284 203);
FORCEPROP 1 LAST CUSTOM_TXT_CDS <CON_PAGE_NUM> OF <CON_TOTAL_PAGES>
J 0
(-546 118);
DISPLAY 0.978723 (-546 118);
FORCEPROP 1 LAST Q_TITLE CPU0 VSS 1/3
J 0
(-9400 150);
DISPLAY 2.446809 (-9400 150);
PAINT GREEN (-9400 150);
FORCEPROP 2 LAST PAGE_BORDER TRUE
J 0
(-7990 5350);
DISPLAY 0.638298 (-7990 5350);
PAINT PINK (-7990 5350);
DISPLAY INVISIBLE (-7990 5350);
FORCEPROP 2 LAST CDS_LIB pure_quanta
J 0
(-100 100);
DISPLAY INVISIBLE (-100 100);
FORCEPROP 1 LAST CDS_LMAN_SYM_OUTLINE -9475,6775,100,-125
J 0
(-100 100);
DISPLAY 0.468085 (-100 100);
PAINT GREEN (-100 100);
DISPLAY INVISIBLE (-100 100);
FORCEPROP 2 LAST CDS_XR_PAGE_TITLE CR-31 : @T6G_MB_LIB.T6G(SCH_1):PAGE31
J 0
(-7990 5350);
DISPLAY 0.638298 (-7990 5350);
PAINT PINK (-7990 5350);
DISPLAY INVISIBLE (-7990 5350);
FORCEPROP 1 LAST Q_DEPT BU9
J 1
(-3863 149);
DISPLAY 1.957447 (-3863 149);
PAINT GREEN (-3863 149);
DISPLAY INVISIBLE (-3863 149);
FORCEPROP 1 LAST COMMENT_BODY TRUE
J 0
(-88 87);
DISPLAY 0.978723 (-88 87);
PAINT GREEN (-88 87);
DISPLAY INVISIBLE (-88 87);
WIRE 16 -1 (-9275 6350)(-9150 6350);
WIRE 16 -1 (-9275 6350)(-9275 6300);
WIRE 16 -1 (-9275 6300)(-9150 6300);
WIRE 16 -1 (-9275 6300)(-9275 6250);
WIRE 16 -1 (-9275 6250)(-9150 6250);
WIRE 16 -1 (-9275 6250)(-9275 6200);
WIRE 16 -1 (-9275 6200)(-9150 6200);
WIRE 16 -1 (-9275 6200)(-9275 6150);
WIRE 16 -1 (-9275 6150)(-9150 6150);
WIRE 16 -1 (-9275 6150)(-9275 6100);
WIRE 16 -1 (-9150 6100)(-9275 6100);
WIRE 16 -1 (-9275 6100)(-9275 6050);
WIRE 16 -1 (-9150 6050)(-9275 6050);
WIRE 16 -1 (-9275 6050)(-9275 6000);
WIRE 16 -1 (-9275 6000)(-9150 6000);
WIRE 16 -1 (-9275 6000)(-9275 5950);
WIRE 16 -1 (-9275 5950)(-9150 5950);
WIRE 16 -1 (-9275 5950)(-9275 5900);
WIRE 16 -1 (-9275 5900)(-9150 5900);
WIRE 16 -1 (-9275 5900)(-9275 5850);
WIRE 16 -1 (-9275 5850)(-9150 5850);
WIRE 16 -1 (-9275 5850)(-9275 5800);
WIRE 16 -1 (-9275 5800)(-9150 5800);
WIRE 16 -1 (-9275 5800)(-9275 5750);
WIRE 16 -1 (-9275 5750)(-9150 5750);
WIRE 16 -1 (-9275 5750)(-9275 5700);
WIRE 16 -1 (-9150 5700)(-9275 5700);
WIRE 16 -1 (-9275 5700)(-9275 5650);
WIRE 16 -1 (-9150 5650)(-9275 5650);
WIRE 16 -1 (-9275 5650)(-9275 5600);
WIRE 16 -1 (-9275 5600)(-9150 5600);
WIRE 16 -1 (-9275 5600)(-9275 5550);
WIRE 16 -1 (-9275 5550)(-9150 5550);
WIRE 16 -1 (-9275 5550)(-9275 5500);
WIRE 16 -1 (-9275 5500)(-9150 5500);
WIRE 16 -1 (-9275 5500)(-9275 5450);
WIRE 16 -1 (-9275 5450)(-9150 5450);
WIRE 16 -1 (-9275 5450)(-9275 5400);
WIRE 16 -1 (-9275 5400)(-9150 5400);
WIRE 16 -1 (-9275 5400)(-9275 5350);
WIRE 16 -1 (-9275 5350)(-9150 5350);
WIRE 16 -1 (-9275 5350)(-9275 5300);
WIRE 16 -1 (-9150 5300)(-9275 5300);
WIRE 16 -1 (-9275 5300)(-9275 5250);
WIRE 16 -1 (-9150 5250)(-9275 5250);
WIRE 16 -1 (-9275 5250)(-9275 5200);
WIRE 16 -1 (-9275 5200)(-9150 5200);
WIRE 16 -1 (-9275 5200)(-9275 5150);
WIRE 16 -1 (-9275 5150)(-9150 5150);
WIRE 16 -1 (-9275 5150)(-9275 5100);
WIRE 16 -1 (-9275 5100)(-9150 5100);
WIRE 16 -1 (-9275 5100)(-9275 5050);
WIRE 16 -1 (-9275 5050)(-9150 5050);
WIRE 16 -1 (-9275 5050)(-9275 5000);
WIRE 16 -1 (-9275 5000)(-9150 5000);
WIRE 16 -1 (-9275 5000)(-9275 4950);
WIRE 16 -1 (-9275 4950)(-9150 4950);
WIRE 16 -1 (-9275 4950)(-9275 4900);
WIRE 16 -1 (-9150 4900)(-9275 4900);
WIRE 16 -1 (-9275 4900)(-9275 4850);
WIRE 16 -1 (-9150 4850)(-9275 4850);
WIRE 16 -1 (-9275 4850)(-9275 4800);
WIRE 16 -1 (-9275 4800)(-9150 4800);
WIRE 16 -1 (-9275 4800)(-9275 4750);
WIRE 16 -1 (-9275 4750)(-9150 4750);
WIRE 16 -1 (-9275 4750)(-9275 4700);
WIRE 16 -1 (-9275 4700)(-9150 4700);
WIRE 16 -1 (-9275 4700)(-9275 4650);
WIRE 16 -1 (-9275 4650)(-9150 4650);
WIRE 16 -1 (-9275 4650)(-9275 4600);
WIRE 16 -1 (-9275 4600)(-9150 4600);
WIRE 16 -1 (-9275 4600)(-9275 4550);
WIRE 16 -1 (-9275 4550)(-9150 4550);
WIRE 16 -1 (-9275 4550)(-9275 4500);
WIRE 16 -1 (-9150 4500)(-9275 4500);
WIRE 16 -1 (-9275 4500)(-9275 4450);
WIRE 16 -1 (-9150 4450)(-9275 4450);
WIRE 16 -1 (-9275 4450)(-9275 4400);
WIRE 16 -1 (-9275 4400)(-9150 4400);
WIRE 16 -1 (-9275 4400)(-9275 4350);
WIRE 16 -1 (-9275 4350)(-9150 4350);
WIRE 16 -1 (-9275 4350)(-9275 4300);
WIRE 16 -1 (-9275 4300)(-9150 4300);
WIRE 16 -1 (-9275 4300)(-9275 4250);
WIRE 16 -1 (-9275 4250)(-9150 4250);
WIRE 16 -1 (-9275 4250)(-9275 4200);
WIRE 16 -1 (-9275 4200)(-9150 4200);
WIRE 16 -1 (-9275 4200)(-9275 4150);
WIRE 16 -1 (-9275 4150)(-9150 4150);
WIRE 16 -1 (-9275 4150)(-9275 4100);
WIRE 16 -1 (-9150 4100)(-9275 4100);
WIRE 16 -1 (-9275 4100)(-9275 4050);
WIRE 16 -1 (-9150 4050)(-9275 4050);
WIRE 16 -1 (-9275 4050)(-9275 4000);
WIRE 16 -1 (-9275 4000)(-9150 4000);
WIRE 16 -1 (-9275 4000)(-9275 3950);
WIRE 16 -1 (-9275 3950)(-9150 3950);
WIRE 16 -1 (-9275 3950)(-9275 3900);
WIRE 16 -1 (-9275 3900)(-9150 3900);
WIRE 16 -1 (-9275 3900)(-9275 3850);
WIRE 16 -1 (-9275 3850)(-9150 3850);
WIRE 16 -1 (-9275 3850)(-9275 3800);
WIRE 16 -1 (-9275 3800)(-9150 3800);
WIRE 16 -1 (-9275 3800)(-9275 3750);
WIRE 16 -1 (-9275 3750)(-9150 3750);
WIRE 16 -1 (-9275 3750)(-9275 3700);
WIRE 16 -1 (-9150 3700)(-9275 3700);
WIRE 16 -1 (-9275 3700)(-9275 3650);
WIRE 16 -1 (-9150 3650)(-9275 3650);
WIRE 16 -1 (-9275 3650)(-9275 3600);
WIRE 16 -1 (-9275 3600)(-9150 3600);
WIRE 16 -1 (-9275 3600)(-9275 3550);
WIRE 16 -1 (-9275 3550)(-9150 3550);
WIRE 16 -1 (-9275 3550)(-9275 3500);
WIRE 16 -1 (-9275 3500)(-9150 3500);
WIRE 16 -1 (-9275 3500)(-9275 3450);
WIRE 16 -1 (-9275 3450)(-9150 3450);
WIRE 16 -1 (-9275 3450)(-9275 3400);
WIRE 16 -1 (-9275 3400)(-9150 3400);
WIRE 16 -1 (-9275 3400)(-9275 3350);
WIRE 16 -1 (-9275 3350)(-9150 3350);
WIRE 16 -1 (-9275 3350)(-9275 3300);
WIRE 16 -1 (-9150 3300)(-9275 3300);
WIRE 16 -1 (-9275 3300)(-9275 3250);
WIRE 16 -1 (-9150 3250)(-9275 3250);
WIRE 16 -1 (-9275 3250)(-9275 3200);
WIRE 16 -1 (-9275 3200)(-9150 3200);
WIRE 16 -1 (-9275 3200)(-9275 3150);
WIRE 16 -1 (-9275 3150)(-9150 3150);
WIRE 16 -1 (-9275 3150)(-9275 3100);
WIRE 16 -1 (-9275 3100)(-9150 3100);
WIRE 16 -1 (-9275 3100)(-9275 3050);
WIRE 16 -1 (-9275 3050)(-9150 3050);
WIRE 16 -1 (-9275 3050)(-9275 3000);
WIRE 16 -1 (-9275 3000)(-9150 3000);
WIRE 16 -1 (-9275 3000)(-9275 2950);
WIRE 16 -1 (-9275 2950)(-9150 2950);
WIRE 16 -1 (-9275 2950)(-9275 2900);
WIRE 16 -1 (-9150 2900)(-9275 2900);
WIRE 16 -1 (-9275 2900)(-9275 2850);
WIRE 16 -1 (-9150 2850)(-9275 2850);
WIRE 16 -1 (-9275 2850)(-9275 2800);
WIRE 16 -1 (-9275 2800)(-9150 2800);
WIRE 16 -1 (-9275 2800)(-9275 2750);
WIRE 16 -1 (-9275 2750)(-9150 2750);
WIRE 16 -1 (-9275 2750)(-9275 2700);
WIRE 16 -1 (-9275 2700)(-9150 2700);
WIRE 16 -1 (-9275 2700)(-9275 2650);
WIRE 16 -1 (-9275 2650)(-9150 2650);
WIRE 16 -1 (-9275 2650)(-9275 2600);
WIRE 16 -1 (-9275 2600)(-9150 2600);
WIRE 16 -1 (-9275 2600)(-9275 2550);
WIRE 16 -1 (-9275 2550)(-9150 2550);
WIRE 16 -1 (-9275 2550)(-9275 2500);
WIRE 16 -1 (-9150 2500)(-9275 2500);
WIRE 16 -1 (-9275 2500)(-9275 2450);
WIRE 16 -1 (-9150 2450)(-9275 2450);
WIRE 16 -1 (-9275 2450)(-9275 2400);
WIRE 16 -1 (-9275 2400)(-9150 2400);
WIRE 16 -1 (-9275 2400)(-9275 2350);
WIRE 16 -1 (-9275 2350)(-9150 2350);
WIRE 16 -1 (-9275 2350)(-9275 2300);
WIRE 16 -1 (-9275 2300)(-9150 2300);
WIRE 16 -1 (-9275 2300)(-9275 2250);
WIRE 16 -1 (-9275 2250)(-9150 2250);
WIRE 16 -1 (-9275 2250)(-9275 2200);
WIRE 16 -1 (-9275 2200)(-9150 2200);
WIRE 16 -1 (-9275 2200)(-9275 2150);
WIRE 16 -1 (-9275 2150)(-9150 2150);
WIRE 16 -1 (-9275 2150)(-9275 2100);
WIRE 16 -1 (-9150 2100)(-9275 2100);
WIRE 16 -1 (-9275 2100)(-9275 2050);
WIRE 16 -1 (-9150 2050)(-9275 2050);
WIRE 16 -1 (-9275 2050)(-9275 2000);
WIRE 16 -1 (-9275 2000)(-9150 2000);
WIRE 16 -1 (-9275 2000)(-9275 1950);
WIRE 16 -1 (-9275 1950)(-9150 1950);
WIRE 16 -1 (-9275 1950)(-9275 1900);
WIRE 16 -1 (-9275 1900)(-9150 1900);
WIRE 16 -1 (-9275 1900)(-9275 1850);
WIRE 16 -1 (-9275 1850)(-9150 1850);
WIRE 16 -1 (-9275 1850)(-9275 1800);
WIRE 16 -1 (-9275 1800)(-9150 1800);
WIRE 16 -1 (-9275 1800)(-9275 1750);
WIRE 16 -1 (-9275 1750)(-9150 1750);
WIRE 16 -1 (-9275 1750)(-9275 1700);
WIRE 16 -1 (-9150 1700)(-9275 1700);
WIRE 16 -1 (-9275 1700)(-9275 1650);
WIRE 16 -1 (-9150 1650)(-9275 1650);
WIRE 16 -1 (-9275 1650)(-9275 1600);
WIRE 16 -1 (-9275 1600)(-9150 1600);
WIRE 16 -1 (-9275 1600)(-9275 1550);
WIRE 16 -1 (-9275 1550)(-9150 1550);
WIRE 16 -1 (-9275 1550)(-9275 1500);
WIRE 16 -1 (-9275 1500)(-9150 1500);
WIRE 16 -1 (-9275 1500)(-9275 1450);
WIRE 16 -1 (-9275 1450)(-9150 1450);
WIRE 16 -1 (-9275 1450)(-9275 1400);
WIRE 16 -1 (-9275 1400)(-9150 1400);
WIRE 16 -1 (-9275 1400)(-9275 1350);
WIRE 16 -1 (-9275 1350)(-9150 1350);
WIRE 16 -1 (-9275 1350)(-9275 1300);
WIRE 16 -1 (-9150 1300)(-9275 1300);
WIRE 16 -1 (-9275 1300)(-9275 1250);
WIRE 16 -1 (-9150 1250)(-9275 1250);
WIRE 16 -1 (-9275 1250)(-9275 1200);
WIRE 16 -1 (-9275 1200)(-9150 1200);
WIRE 16 -1 (-9275 1200)(-9275 1150);
WIRE 16 -1 (-9275 1150)(-9150 1150);
WIRE 16 -1 (-9275 1150)(-9275 1100);
WIRE 16 -1 (-9275 1100)(-9150 1100);
WIRE 16 -1 (-9275 1100)(-9275 1050);
WIRE 16 -1 (-9275 1050)(-9150 1050);
WIRE 16 -1 (-9275 1050)(-9275 1000);
WIRE 16 -1 (-9275 1000)(-9150 1000);
WIRE 16 -1 (-9275 1000)(-9275 950);
WIRE 16 -1 (-9275 950)(-9150 950);
WIRE 16 -1 (-9275 950)(-9275 900);
WIRE 16 -1 (-9150 900)(-9275 900);
WIRE 16 -1 (-9275 900)(-9275 850);
WIRE 16 -1 (-9150 850)(-9275 850);
WIRE 16 -1 (-9275 850)(-9275 800);
WIRE 16 -1 (-9150 800)(-9275 800);
WIRE 16 -1 (-9275 800)(-9275 750);
WIRE 16 -1 (-9150 750)(-9275 750);
WIRE 16 -1 (-9275 750)(-9275 700);
WIRE 16 -1 (-9150 700)(-9275 700);
WIRE 16 -1 (-9275 700)(-9275 650);
WIRE 16 -1 (-9150 650)(-9275 650);
WIRE 16 -1 (-9275 650)(-9275 600);
WIRE 16 -1 (-9150 600)(-9275 600);
WIRE 16 -1 (-9275 600)(-9275 550);
WIRE 16 -1 (-9150 550)(-9275 550);
WIRE 16 -1 (-9275 550)(-9275 500);
WIRE 16 -1 (-9275 500)(-9150 500);
WIRE 16 -1 (-9275 500)(-9275 450);
WIRE 16 -1 (-9275 450)(-9150 450);
WIRE 16 -1 (-9275 450)(-9275 400);
WIRE 16 -1 (-7925 6350)(-7925 6300);
WIRE 16 -1 (-7925 6350)(-8050 6350);
WIRE 16 -1 (-7925 6300)(-7925 6250);
WIRE 16 -1 (-7925 6300)(-8050 6300);
WIRE 16 -1 (-7925 6250)(-7925 6200);
WIRE 16 -1 (-8050 6250)(-7925 6250);
WIRE 16 -1 (-7925 6200)(-7925 6150);
WIRE 16 -1 (-8050 6200)(-7925 6200);
WIRE 16 -1 (-8050 6150)(-7925 6150);
WIRE 16 -1 (-7925 6150)(-7925 6100);
WIRE 16 -1 (-7925 6100)(-7925 6050);
WIRE 16 -1 (-8050 6100)(-7925 6100);
WIRE 16 -1 (-7925 6050)(-7925 6000);
WIRE 16 -1 (-8050 6050)(-7925 6050);
WIRE 16 -1 (-7925 6000)(-7925 5950);
WIRE 16 -1 (-8050 6000)(-7925 6000);
WIRE 16 -1 (-7925 5950)(-7925 5900);
WIRE 16 -1 (-8050 5950)(-7925 5950);
WIRE 16 -1 (-7925 5900)(-7925 5850);
WIRE 16 -1 (-8050 5900)(-7925 5900);
WIRE 16 -1 (-7925 5850)(-7925 5800);
WIRE 16 -1 (-7925 5850)(-8050 5850);
WIRE 16 -1 (-7925 5800)(-7925 5750);
WIRE 16 -1 (-7925 5800)(-8050 5800);
WIRE 16 -1 (-7925 5750)(-7925 5700);
WIRE 16 -1 (-7925 5750)(-8050 5750);
WIRE 16 -1 (-7925 5700)(-7925 5650);
WIRE 16 -1 (-7925 5700)(-8050 5700);
WIRE 16 -1 (-7925 5650)(-8050 5650);
WIRE 16 -1 (-7925 5650)(-7925 5600);
WIRE 16 -1 (-7925 5600)(-7925 5550);
WIRE 16 -1 (-7925 5600)(-8050 5600);
WIRE 16 -1 (-7925 5550)(-7925 5500);
WIRE 16 -1 (-8050 5550)(-7925 5550);
WIRE 16 -1 (-7925 5500)(-7925 5450);
WIRE 16 -1 (-8050 5500)(-7925 5500);
WIRE 16 -1 (-7925 5450)(-7925 5400);
WIRE 16 -1 (-7925 5450)(-8050 5450);
WIRE 16 -1 (-7925 5400)(-7925 5350);
WIRE 16 -1 (-7925 5400)(-8050 5400);
WIRE 16 -1 (-7925 5350)(-7925 5300);
WIRE 16 -1 (-7925 5350)(-8050 5350);
WIRE 16 -1 (-7925 5300)(-7925 5250);
WIRE 16 -1 (-7925 5300)(-8050 5300);
WIRE 16 -1 (-7925 5250)(-7925 5200);
WIRE 16 -1 (-7925 5250)(-8050 5250);
WIRE 16 -1 (-7925 5200)(-7925 5150);
WIRE 16 -1 (-7925 5200)(-8050 5200);
WIRE 16 -1 (-8050 5150)(-7925 5150);
WIRE 16 -1 (-7925 5150)(-7925 5100);
WIRE 16 -1 (-7925 5100)(-7925 5050);
WIRE 16 -1 (-8050 5100)(-7925 5100);
WIRE 16 -1 (-7925 5050)(-7925 5000);
WIRE 16 -1 (-7925 5050)(-8050 5050);
WIRE 16 -1 (-7925 5000)(-7925 4950);
WIRE 16 -1 (-7925 5000)(-8050 5000);
WIRE 16 -1 (-7925 4950)(-7925 4900);
WIRE 16 -1 (-7925 4950)(-8050 4950);
WIRE 16 -1 (-7925 4900)(-7925 4850);
WIRE 16 -1 (-7925 4900)(-8050 4900);
WIRE 16 -1 (-7925 4850)(-7925 4800);
WIRE 16 -1 (-7925 4850)(-8050 4850);
WIRE 16 -1 (-7925 4800)(-7925 4750);
WIRE 16 -1 (-7925 4800)(-8050 4800);
WIRE 16 -1 (-7925 4750)(-7925 4700);
WIRE 16 -1 (-8050 4750)(-7925 4750);
WIRE 16 -1 (-7925 4700)(-7925 4650);
WIRE 16 -1 (-8050 4700)(-7925 4700);
WIRE 16 -1 (-7925 4650)(-8050 4650);
WIRE 16 -1 (-7925 4650)(-7925 4600);
WIRE 16 -1 (-7925 4600)(-7925 4550);
WIRE 16 -1 (-7925 4600)(-8050 4600);
WIRE 16 -1 (-7925 4550)(-7925 4500);
WIRE 16 -1 (-7925 4550)(-8050 4550);
WIRE 16 -1 (-7925 4500)(-7925 4450);
WIRE 16 -1 (-7925 4500)(-8050 4500);
WIRE 16 -1 (-7925 4450)(-7925 4400);
WIRE 16 -1 (-7925 4450)(-8050 4450);
WIRE 16 -1 (-7925 4400)(-7925 4350);
WIRE 16 -1 (-7925 4400)(-8050 4400);
WIRE 16 -1 (-7925 4350)(-7925 4300);
WIRE 16 -1 (-8050 4350)(-7925 4350);
WIRE 16 -1 (-7925 4300)(-7925 4250);
WIRE 16 -1 (-8050 4300)(-7925 4300);
WIRE 16 -1 (-7925 4250)(-7925 4200);
WIRE 16 -1 (-7925 4250)(-8050 4250);
WIRE 16 -1 (-7925 4200)(-7925 4150);
WIRE 16 -1 (-7925 4200)(-8050 4200);
WIRE 16 -1 (-7925 4150)(-7925 4100);
WIRE 16 -1 (-7925 4150)(-8050 4150);
WIRE 16 -1 (-7925 4100)(-8050 4100);
WIRE 16 -1 (-7925 4100)(-7925 4050);
WIRE 16 -1 (-7925 4050)(-7925 4000);
WIRE 16 -1 (-7925 4050)(-8050 4050);
WIRE 16 -1 (-7925 4000)(-7925 3950);
WIRE 16 -1 (-7925 4000)(-8050 4000);
WIRE 16 -1 (-7925 3950)(-7925 3900);
WIRE 16 -1 (-8050 3950)(-7925 3950);
WIRE 16 -1 (-7925 3900)(-7925 3850);
WIRE 16 -1 (-8050 3900)(-7925 3900);
WIRE 16 -1 (-7925 3850)(-7925 3800);
WIRE 16 -1 (-7925 3850)(-8050 3850);
WIRE 16 -1 (-7925 3800)(-7925 3750);
WIRE 16 -1 (-7925 3800)(-8050 3800);
WIRE 16 -1 (-7925 3750)(-7925 3700);
WIRE 16 -1 (-7925 3750)(-8050 3750);
WIRE 16 -1 (-7925 3700)(-7925 3650);
WIRE 16 -1 (-7925 3700)(-8050 3700);
WIRE 16 -1 (-7925 3650)(-7925 3600);
WIRE 16 -1 (-7925 3650)(-8050 3650);
WIRE 16 -1 (-7925 3600)(-8050 3600);
WIRE 16 -1 (-7925 3600)(-7925 3550);
WIRE 16 -1 (-7925 3550)(-7925 3500);
WIRE 16 -1 (-8050 3550)(-7925 3550);
WIRE 16 -1 (-7925 3500)(-7925 3450);
WIRE 16 -1 (-8050 3500)(-7925 3500);
WIRE 16 -1 (-7925 3450)(-7925 3400);
WIRE 16 -1 (-7925 3450)(-8050 3450);
WIRE 16 -1 (-7925 3400)(-7925 3350);
WIRE 16 -1 (-7925 3400)(-8050 3400);
WIRE 16 -1 (-7925 3350)(-7925 3300);
WIRE 16 -1 (-7925 3350)(-8050 3350);
WIRE 16 -1 (-7925 3300)(-7925 3250);
WIRE 16 -1 (-7925 3300)(-8050 3300);
WIRE 16 -1 (-7925 3250)(-7925 3200);
WIRE 16 -1 (-7925 3250)(-8050 3250);
WIRE 16 -1 (-7925 3200)(-7925 3150);
WIRE 16 -1 (-7925 3200)(-8050 3200);
WIRE 16 -1 (-7925 3150)(-7925 3100);
WIRE 16 -1 (-8050 3150)(-7925 3150);
WIRE 16 -1 (-8050 3100)(-7925 3100);
WIRE 16 -1 (-7925 3100)(-7925 3050);
WIRE 16 -1 (-7925 3050)(-7925 3000);
WIRE 16 -1 (-7925 3050)(-8050 3050);
WIRE 16 -1 (-7925 3000)(-7925 2950);
WIRE 16 -1 (-7925 3000)(-8050 3000);
WIRE 16 -1 (-7925 2950)(-7925 2900);
WIRE 16 -1 (-7925 2950)(-8050 2950);
WIRE 16 -1 (-7925 2900)(-7925 2850);
WIRE 16 -1 (-7925 2900)(-8050 2900);
WIRE 16 -1 (-7925 2850)(-7925 2800);
WIRE 16 -1 (-7925 2850)(-8050 2850);
WIRE 16 -1 (-7925 2800)(-7925 2750);
WIRE 16 -1 (-7925 2800)(-8050 2800);
WIRE 16 -1 (-7925 2750)(-7925 2700);
WIRE 16 -1 (-8050 2750)(-7925 2750);
WIRE 16 -1 (-7925 2700)(-7925 2650);
WIRE 16 -1 (-8050 2700)(-7925 2700);
WIRE 16 -1 (-7925 2650)(-7925 2600);
WIRE 16 -1 (-7925 2650)(-8050 2650);
WIRE 16 -1 (-7925 2600)(-8050 2600);
WIRE 16 -1 (-7925 2600)(-7925 2550);
WIRE 16 -1 (-7925 2550)(-7925 2500);
WIRE 16 -1 (-7925 2550)(-8050 2550);
WIRE 16 -1 (-7925 2500)(-7925 2450);
WIRE 16 -1 (-7925 2500)(-8050 2500);
WIRE 16 -1 (-7925 2450)(-7925 2400);
WIRE 16 -1 (-7925 2450)(-8050 2450);
WIRE 16 -1 (-7925 2400)(-7925 2350);
WIRE 16 -1 (-7925 2400)(-8050 2400);
WIRE 16 -1 (-7925 2350)(-7925 2300);
WIRE 16 -1 (-8050 2350)(-7925 2350);
WIRE 16 -1 (-7925 2300)(-7925 2250);
WIRE 16 -1 (-8050 2300)(-7925 2300);
WIRE 16 -1 (-7925 2250)(-7925 2200);
WIRE 16 -1 (-7925 2250)(-8050 2250);
WIRE 16 -1 (-7925 2200)(-7925 2150);
WIRE 16 -1 (-7925 2200)(-8050 2200);
WIRE 16 -1 (-7925 2150)(-7925 2100);
WIRE 16 -1 (-7925 2150)(-8050 2150);
WIRE 16 -1 (-7925 2100)(-7925 2050);
WIRE 16 -1 (-7925 2100)(-8050 2100);
WIRE 16 -1 (-7925 2050)(-8050 2050);
WIRE 16 -1 (-7925 2050)(-7925 2000);
WIRE 16 -1 (-7925 2000)(-7925 1950);
WIRE 16 -1 (-7925 2000)(-8050 2000);
WIRE 16 -1 (-7925 1950)(-7925 1900);
WIRE 16 -1 (-8050 1950)(-7925 1950);
WIRE 16 -1 (-7925 1900)(-7925 1850);
WIRE 16 -1 (-8050 1900)(-7925 1900);
WIRE 16 -1 (-7925 1850)(-7925 1800);
WIRE 16 -1 (-7925 1850)(-8050 1850);
WIRE 16 -1 (-7925 1800)(-7925 1750);
WIRE 16 -1 (-7925 1800)(-8050 1800);
WIRE 16 -1 (-7925 1750)(-7925 1700);
WIRE 16 -1 (-7925 1750)(-8050 1750);
WIRE 16 -1 (-7925 1700)(-7925 1650);
WIRE 16 -1 (-7925 1700)(-8050 1700);
WIRE 16 -1 (-7925 1650)(-7925 1600);
WIRE 16 -1 (-7925 1650)(-8050 1650);
WIRE 16 -1 (-7925 1600)(-7925 1550);
WIRE 16 -1 (-7925 1600)(-8050 1600);
WIRE 16 -1 (-8050 1550)(-7925 1550);
WIRE 16 -1 (-7925 1550)(-7925 1500);
WIRE 16 -1 (-7925 1500)(-7925 1450);
WIRE 16 -1 (-8050 1500)(-7925 1500);
WIRE 16 -1 (-7925 1450)(-7925 1400);
WIRE 16 -1 (-7925 1450)(-8050 1450);
WIRE 16 -1 (-7925 1400)(-7925 1350);
WIRE 16 -1 (-7925 1400)(-8050 1400);
WIRE 16 -1 (-7925 1350)(-7925 1300);
WIRE 16 -1 (-7925 1350)(-8050 1350);
WIRE 16 -1 (-7925 1300)(-7925 1250);
WIRE 16 -1 (-7925 1300)(-8050 1300);
WIRE 16 -1 (-7925 1250)(-7925 1200);
WIRE 16 -1 (-7925 1250)(-8050 1250);
WIRE 16 -1 (-7925 1200)(-7925 1150);
WIRE 16 -1 (-7925 1200)(-8050 1200);
WIRE 16 -1 (-7925 1150)(-7925 1100);
WIRE 16 -1 (-8050 1150)(-7925 1150);
WIRE 16 -1 (-7925 1100)(-7925 1050);
WIRE 16 -1 (-8050 1100)(-7925 1100);
WIRE 16 -1 (-7925 1050)(-8050 1050);
WIRE 16 -1 (-7925 1050)(-7925 1000);
WIRE 16 -1 (-7925 1000)(-7925 950);
WIRE 16 -1 (-7925 1000)(-8050 1000);
WIRE 16 -1 (-7925 950)(-7925 900);
WIRE 16 -1 (-7925 950)(-8050 950);
WIRE 16 -1 (-7925 900)(-7925 850);
WIRE 16 -1 (-7925 900)(-8050 900);
WIRE 16 -1 (-7925 850)(-7925 800);
WIRE 16 -1 (-7925 850)(-8050 850);
WIRE 16 -1 (-7925 800)(-7925 750);
WIRE 16 -1 (-7925 800)(-8050 800);
WIRE 16 -1 (-7925 750)(-7925 700);
WIRE 16 -1 (-8050 750)(-7925 750);
WIRE 16 -1 (-7925 700)(-7925 650);
WIRE 16 -1 (-8050 700)(-7925 700);
WIRE 16 -1 (-7925 650)(-7925 600);
WIRE 16 -1 (-7925 650)(-8050 650);
WIRE 16 -1 (-7925 600)(-7925 550);
WIRE 16 -1 (-7925 600)(-8050 600);
WIRE 16 -1 (-7925 550)(-8050 550);
WIRE 16 -1 (-7925 550)(-7925 500);
WIRE 16 -1 (-7925 500)(-7925 450);
WIRE 16 -1 (-7925 500)(-8050 500);
WIRE 16 -1 (-7925 450)(-7925 425);
WIRE 16 -1 (-7925 450)(-8050 450);
WIRE 16 -1 (-7750 6275)(-7625 6275);
WIRE 16 -1 (-7750 6275)(-7750 6225);
WIRE 16 -1 (-7750 6225)(-7625 6225);
WIRE 16 -1 (-7750 6225)(-7750 6175);
WIRE 16 -1 (-7750 6175)(-7625 6175);
WIRE 16 -1 (-7750 6175)(-7750 6125);
WIRE 16 -1 (-7750 6125)(-7625 6125);
WIRE 16 -1 (-7750 6125)(-7750 6075);
WIRE 16 -1 (-7750 6075)(-7625 6075);
WIRE 16 -1 (-7750 6075)(-7750 6025);
WIRE 16 -1 (-7625 6025)(-7750 6025);
WIRE 16 -1 (-7750 6025)(-7750 5975);
WIRE 16 -1 (-7625 5975)(-7750 5975);
WIRE 16 -1 (-7750 5975)(-7750 5925);
WIRE 16 -1 (-7750 5925)(-7625 5925);
WIRE 16 -1 (-7750 5925)(-7750 5875);
WIRE 16 -1 (-7750 5875)(-7625 5875);
WIRE 16 -1 (-7750 5875)(-7750 5825);
WIRE 16 -1 (-7750 5825)(-7625 5825);
WIRE 16 -1 (-7750 5825)(-7750 5775);
WIRE 16 -1 (-7750 5775)(-7625 5775);
WIRE 16 -1 (-7750 5775)(-7750 5725);
WIRE 16 -1 (-7750 5725)(-7625 5725);
WIRE 16 -1 (-7750 5725)(-7750 5675);
WIRE 16 -1 (-7750 5675)(-7625 5675);
WIRE 16 -1 (-7750 5675)(-7750 5625);
WIRE 16 -1 (-7625 5625)(-7750 5625);
WIRE 16 -1 (-7750 5625)(-7750 5575);
WIRE 16 -1 (-7625 5575)(-7750 5575);
WIRE 16 -1 (-7750 5575)(-7750 5525);
WIRE 16 -1 (-7750 5525)(-7625 5525);
WIRE 16 -1 (-7750 5525)(-7750 5475);
WIRE 16 -1 (-7750 5475)(-7625 5475);
WIRE 16 -1 (-7750 5475)(-7750 5425);
WIRE 16 -1 (-7750 5425)(-7625 5425);
WIRE 16 -1 (-7750 5425)(-7750 5375);
WIRE 16 -1 (-7750 5375)(-7625 5375);
WIRE 16 -1 (-7750 5375)(-7750 5325);
WIRE 16 -1 (-7750 5325)(-7625 5325);
WIRE 16 -1 (-7750 5325)(-7750 5275);
WIRE 16 -1 (-7750 5275)(-7625 5275);
WIRE 16 -1 (-7750 5275)(-7750 5225);
WIRE 16 -1 (-7625 5225)(-7750 5225);
WIRE 16 -1 (-7750 5225)(-7750 5175);
WIRE 16 -1 (-7625 5175)(-7750 5175);
WIRE 16 -1 (-7750 5175)(-7750 5125);
WIRE 16 -1 (-7750 5125)(-7625 5125);
WIRE 16 -1 (-7750 5125)(-7750 5075);
WIRE 16 -1 (-7750 5075)(-7625 5075);
WIRE 16 -1 (-7750 5075)(-7750 5025);
WIRE 16 -1 (-7750 5025)(-7625 5025);
WIRE 16 -1 (-7750 5025)(-7750 4975);
WIRE 16 -1 (-7750 4975)(-7625 4975);
WIRE 16 -1 (-7750 4975)(-7750 4925);
WIRE 16 -1 (-7750 4925)(-7625 4925);
WIRE 16 -1 (-7750 4925)(-7750 4875);
WIRE 16 -1 (-7750 4875)(-7625 4875);
WIRE 16 -1 (-7750 4875)(-7750 4825);
WIRE 16 -1 (-7625 4825)(-7750 4825);
WIRE 16 -1 (-7750 4825)(-7750 4775);
WIRE 16 -1 (-7625 4775)(-7750 4775);
WIRE 16 -1 (-7750 4775)(-7750 4725);
WIRE 16 -1 (-7750 4725)(-7625 4725);
WIRE 16 -1 (-7750 4725)(-7750 4675);
WIRE 16 -1 (-7750 4675)(-7625 4675);
WIRE 16 -1 (-7750 4675)(-7750 4625);
WIRE 16 -1 (-7750 4625)(-7625 4625);
WIRE 16 -1 (-7750 4625)(-7750 4575);
WIRE 16 -1 (-7750 4575)(-7625 4575);
WIRE 16 -1 (-7750 4575)(-7750 4525);
WIRE 16 -1 (-7750 4525)(-7625 4525);
WIRE 16 -1 (-7750 4525)(-7750 4475);
WIRE 16 -1 (-7750 4475)(-7625 4475);
WIRE 16 -1 (-7750 4475)(-7750 4425);
WIRE 16 -1 (-7625 4425)(-7750 4425);
WIRE 16 -1 (-7750 4425)(-7750 4375);
WIRE 16 -1 (-7625 4375)(-7750 4375);
WIRE 16 -1 (-7750 4375)(-7750 4325);
WIRE 16 -1 (-7750 4325)(-7625 4325);
WIRE 16 -1 (-7750 4325)(-7750 4275);
WIRE 16 -1 (-7750 4275)(-7625 4275);
WIRE 16 -1 (-7750 4275)(-7750 4225);
WIRE 16 -1 (-7750 4225)(-7625 4225);
WIRE 16 -1 (-7750 4225)(-7750 4175);
WIRE 16 -1 (-7750 4175)(-7625 4175);
WIRE 16 -1 (-7750 4175)(-7750 4125);
WIRE 16 -1 (-7750 4125)(-7625 4125);
WIRE 16 -1 (-7750 4125)(-7750 4075);
WIRE 16 -1 (-7750 4075)(-7625 4075);
WIRE 16 -1 (-7750 4075)(-7750 4025);
WIRE 16 -1 (-7625 4025)(-7750 4025);
WIRE 16 -1 (-7750 4025)(-7750 3975);
WIRE 16 -1 (-7625 3975)(-7750 3975);
WIRE 16 -1 (-7750 3975)(-7750 3925);
WIRE 16 -1 (-7750 3925)(-7625 3925);
WIRE 16 -1 (-7750 3925)(-7750 3875);
WIRE 16 -1 (-7750 3875)(-7625 3875);
WIRE 16 -1 (-7750 3875)(-7750 3825);
WIRE 16 -1 (-7750 3825)(-7625 3825);
WIRE 16 -1 (-7750 3825)(-7750 3775);
WIRE 16 -1 (-7750 3775)(-7625 3775);
WIRE 16 -1 (-7750 3775)(-7750 3725);
WIRE 16 -1 (-7750 3725)(-7625 3725);
WIRE 16 -1 (-7750 3725)(-7750 3675);
WIRE 16 -1 (-7750 3675)(-7625 3675);
WIRE 16 -1 (-7750 3675)(-7750 3625);
WIRE 16 -1 (-7625 3625)(-7750 3625);
WIRE 16 -1 (-7750 3625)(-7750 3575);
WIRE 16 -1 (-7625 3575)(-7750 3575);
WIRE 16 -1 (-7750 3575)(-7750 3525);
WIRE 16 -1 (-7750 3525)(-7625 3525);
WIRE 16 -1 (-7750 3525)(-7750 3475);
WIRE 16 -1 (-7750 3475)(-7625 3475);
WIRE 16 -1 (-7750 3475)(-7750 3425);
WIRE 16 -1 (-7750 3425)(-7625 3425);
WIRE 16 -1 (-7750 3425)(-7750 3375);
WIRE 16 -1 (-7750 3375)(-7625 3375);
WIRE 16 -1 (-7750 3375)(-7750 3325);
WIRE 16 -1 (-7750 3325)(-7625 3325);
WIRE 16 -1 (-7750 3325)(-7750 3275);
WIRE 16 -1 (-7750 3275)(-7625 3275);
WIRE 16 -1 (-7750 3275)(-7750 3225);
WIRE 16 -1 (-7625 3225)(-7750 3225);
WIRE 16 -1 (-7750 3225)(-7750 3175);
WIRE 16 -1 (-7625 3175)(-7750 3175);
WIRE 16 -1 (-7750 3175)(-7750 3125);
WIRE 16 -1 (-7750 3125)(-7625 3125);
WIRE 16 -1 (-7750 3125)(-7750 3075);
WIRE 16 -1 (-7750 3075)(-7625 3075);
WIRE 16 -1 (-7750 3075)(-7750 3025);
WIRE 16 -1 (-7750 3025)(-7625 3025);
WIRE 16 -1 (-7750 3025)(-7750 2975);
WIRE 16 -1 (-7750 2975)(-7625 2975);
WIRE 16 -1 (-7750 2975)(-7750 2925);
WIRE 16 -1 (-7750 2925)(-7625 2925);
WIRE 16 -1 (-7750 2925)(-7750 2875);
WIRE 16 -1 (-7750 2875)(-7625 2875);
WIRE 16 -1 (-7750 2875)(-7750 2825);
WIRE 16 -1 (-7625 2825)(-7750 2825);
WIRE 16 -1 (-7750 2825)(-7750 2775);
WIRE 16 -1 (-7625 2775)(-7750 2775);
WIRE 16 -1 (-7750 2775)(-7750 2725);
WIRE 16 -1 (-7750 2725)(-7625 2725);
WIRE 16 -1 (-7750 2725)(-7750 2675);
WIRE 16 -1 (-7750 2675)(-7625 2675);
WIRE 16 -1 (-7750 2675)(-7750 2625);
WIRE 16 -1 (-7750 2625)(-7625 2625);
WIRE 16 -1 (-7750 2625)(-7750 2575);
WIRE 16 -1 (-7750 2575)(-7625 2575);
WIRE 16 -1 (-7750 2575)(-7750 2525);
WIRE 16 -1 (-7750 2525)(-7625 2525);
WIRE 16 -1 (-7750 2525)(-7750 2475);
WIRE 16 -1 (-7750 2475)(-7625 2475);
WIRE 16 -1 (-7750 2475)(-7750 2425);
WIRE 16 -1 (-7625 2425)(-7750 2425);
WIRE 16 -1 (-7750 2425)(-7750 2375);
WIRE 16 -1 (-7625 2375)(-7750 2375);
WIRE 16 -1 (-7750 2375)(-7750 2325);
WIRE 16 -1 (-7750 2325)(-7625 2325);
WIRE 16 -1 (-7750 2325)(-7750 2275);
WIRE 16 -1 (-7750 2275)(-7625 2275);
WIRE 16 -1 (-7750 2275)(-7750 2225);
WIRE 16 -1 (-7750 2225)(-7625 2225);
WIRE 16 -1 (-7750 2225)(-7750 2175);
WIRE 16 -1 (-7750 2175)(-7625 2175);
WIRE 16 -1 (-7750 2175)(-7750 2125);
WIRE 16 -1 (-7750 2125)(-7625 2125);
WIRE 16 -1 (-7750 2125)(-7750 2075);
WIRE 16 -1 (-7750 2075)(-7625 2075);
WIRE 16 -1 (-7750 2075)(-7750 2025);
WIRE 16 -1 (-7625 2025)(-7750 2025);
WIRE 16 -1 (-7750 2025)(-7750 1975);
WIRE 16 -1 (-7625 1975)(-7750 1975);
WIRE 16 -1 (-7750 1975)(-7750 1925);
WIRE 16 -1 (-7750 1925)(-7625 1925);
WIRE 16 -1 (-7750 1925)(-7750 1875);
WIRE 16 -1 (-7750 1875)(-7625 1875);
WIRE 16 -1 (-7750 1875)(-7750 1825);
WIRE 16 -1 (-7750 1825)(-7625 1825);
WIRE 16 -1 (-7750 1825)(-7750 1775);
WIRE 16 -1 (-7750 1775)(-7625 1775);
WIRE 16 -1 (-7750 1775)(-7750 1725);
WIRE 16 -1 (-7750 1725)(-7625 1725);
WIRE 16 -1 (-7750 1725)(-7750 1675);
WIRE 16 -1 (-7750 1675)(-7625 1675);
WIRE 16 -1 (-7750 1675)(-7750 1625);
WIRE 16 -1 (-7625 1625)(-7750 1625);
WIRE 16 -1 (-7750 1625)(-7750 1575);
WIRE 16 -1 (-7625 1575)(-7750 1575);
WIRE 16 -1 (-7750 1575)(-7750 1525);
WIRE 16 -1 (-7750 1525)(-7625 1525);
WIRE 16 -1 (-7750 1525)(-7750 1475);
WIRE 16 -1 (-7750 1475)(-7625 1475);
WIRE 16 -1 (-7750 1475)(-7750 1425);
WIRE 16 -1 (-7750 1425)(-7625 1425);
WIRE 16 -1 (-7750 1425)(-7750 1375);
WIRE 16 -1 (-7750 1375)(-7625 1375);
WIRE 16 -1 (-7750 1375)(-7750 1325);
WIRE 16 -1 (-7750 1325)(-7625 1325);
WIRE 16 -1 (-7750 1325)(-7750 1275);
WIRE 16 -1 (-7750 1275)(-7625 1275);
WIRE 16 -1 (-7750 1275)(-7750 1225);
WIRE 16 -1 (-7625 1225)(-7750 1225);
WIRE 16 -1 (-7750 1225)(-7750 1175);
WIRE 16 -1 (-7625 1175)(-7750 1175);
WIRE 16 -1 (-7750 1175)(-7750 1125);
WIRE 16 -1 (-7750 1125)(-7625 1125);
WIRE 16 -1 (-7750 1125)(-7750 1075);
WIRE 16 -1 (-7750 1075)(-7625 1075);
WIRE 16 -1 (-7750 1075)(-7750 1025);
WIRE 16 -1 (-7750 1025)(-7625 1025);
WIRE 16 -1 (-7750 1025)(-7750 975);
WIRE 16 -1 (-7750 975)(-7625 975);
WIRE 16 -1 (-7750 975)(-7750 925);
WIRE 16 -1 (-7750 925)(-7625 925);
WIRE 16 -1 (-7750 925)(-7750 875);
WIRE 16 -1 (-7750 875)(-7625 875);
WIRE 16 -1 (-7750 875)(-7750 825);
WIRE 16 -1 (-7625 825)(-7750 825);
WIRE 16 -1 (-7750 825)(-7750 775);
WIRE 16 -1 (-7625 775)(-7750 775);
WIRE 16 -1 (-7750 775)(-7750 725);
WIRE 16 -1 (-7625 725)(-7750 725);
WIRE 16 -1 (-7750 725)(-7750 675);
WIRE 16 -1 (-7625 675)(-7750 675);
WIRE 16 -1 (-7750 675)(-7750 625);
WIRE 16 -1 (-7625 625)(-7750 625);
WIRE 16 -1 (-7750 625)(-7750 575);
WIRE 16 -1 (-7625 575)(-7750 575);
WIRE 16 -1 (-7750 575)(-7750 525);
WIRE 16 -1 (-7625 525)(-7750 525);
WIRE 16 -1 (-7750 525)(-7750 475);
WIRE 16 -1 (-7625 475)(-7750 475);
WIRE 16 -1 (-7750 475)(-7750 425);
WIRE 16 -1 (-6525 6275)(-6400 6275);
WIRE 16 -1 (-6400 6275)(-6400 6225);
WIRE 16 -1 (-6525 6225)(-6400 6225);
WIRE 16 -1 (-6400 6225)(-6400 6175);
WIRE 16 -1 (-6525 6175)(-6400 6175);
WIRE 16 -1 (-6400 6175)(-6400 6125);
WIRE 16 -1 (-6525 6125)(-6400 6125);
WIRE 16 -1 (-6400 6125)(-6400 6075);
WIRE 16 -1 (-6525 6075)(-6400 6075);
WIRE 16 -1 (-6400 6075)(-6400 6025);
WIRE 16 -1 (-6525 6025)(-6400 6025);
WIRE 16 -1 (-6400 6025)(-6400 5975);
WIRE 16 -1 (-6525 5975)(-6400 5975);
WIRE 16 -1 (-6400 5975)(-6400 5925);
WIRE 16 -1 (-6525 5925)(-6400 5925);
WIRE 16 -1 (-6400 5925)(-6400 5875);
WIRE 16 -1 (-6400 5875)(-6525 5875);
WIRE 16 -1 (-6400 5875)(-6400 5825);
WIRE 16 -1 (-6400 5825)(-6525 5825);
WIRE 16 -1 (-6400 5825)(-6400 5775);
WIRE 16 -1 (-6400 5775)(-6525 5775);
WIRE 16 -1 (-6400 5775)(-6400 5725);
WIRE 16 -1 (-6400 5725)(-6525 5725);
WIRE 16 -1 (-6400 5725)(-6400 5675);
WIRE 16 -1 (-6400 5675)(-6525 5675);
WIRE 16 -1 (-6400 5675)(-6400 5625);
WIRE 16 -1 (-6400 5625)(-6525 5625);
WIRE 16 -1 (-6400 5625)(-6400 5575);
WIRE 16 -1 (-6525 5575)(-6400 5575);
WIRE 16 -1 (-6400 5575)(-6400 5525);
WIRE 16 -1 (-6525 5525)(-6400 5525);
WIRE 16 -1 (-6400 5525)(-6400 5475);
WIRE 16 -1 (-6400 5475)(-6525 5475);
WIRE 16 -1 (-6400 5475)(-6400 5425);
WIRE 16 -1 (-6400 5425)(-6525 5425);
WIRE 16 -1 (-6400 5425)(-6400 5375);
WIRE 16 -1 (-6400 5375)(-6525 5375);
WIRE 16 -1 (-6400 5375)(-6400 5325);
WIRE 16 -1 (-6400 5325)(-6525 5325);
WIRE 16 -1 (-6400 5325)(-6400 5275);
WIRE 16 -1 (-6400 5275)(-6525 5275);
WIRE 16 -1 (-6400 5275)(-6400 5225);
WIRE 16 -1 (-6400 5225)(-6525 5225);
WIRE 16 -1 (-6400 5225)(-6400 5175);
WIRE 16 -1 (-6525 5175)(-6400 5175);
WIRE 16 -1 (-6400 5175)(-6400 5125);
WIRE 16 -1 (-6525 5125)(-6400 5125);
WIRE 16 -1 (-6400 5125)(-6400 5075);
WIRE 16 -1 (-6400 5075)(-6525 5075);
WIRE 16 -1 (-6400 5075)(-6400 5025);
WIRE 16 -1 (-6400 5025)(-6525 5025);
WIRE 16 -1 (-6400 5025)(-6400 4975);
WIRE 16 -1 (-6400 4975)(-6525 4975);
WIRE 16 -1 (-6400 4975)(-6400 4925);
WIRE 16 -1 (-6400 4925)(-6525 4925);
WIRE 16 -1 (-6400 4925)(-6400 4875);
WIRE 16 -1 (-6400 4875)(-6525 4875);
WIRE 16 -1 (-6400 4875)(-6400 4825);
WIRE 16 -1 (-6400 4825)(-6525 4825);
WIRE 16 -1 (-6400 4825)(-6400 4775);
WIRE 16 -1 (-6525 4775)(-6400 4775);
WIRE 16 -1 (-6400 4775)(-6400 4725);
WIRE 16 -1 (-6525 4725)(-6400 4725);
WIRE 16 -1 (-6400 4725)(-6400 4675);
WIRE 16 -1 (-6400 4675)(-6525 4675);
WIRE 16 -1 (-6400 4675)(-6400 4625);
WIRE 16 -1 (-6400 4625)(-6525 4625);
WIRE 16 -1 (-6400 4625)(-6400 4575);
WIRE 16 -1 (-6400 4575)(-6525 4575);
WIRE 16 -1 (-6400 4575)(-6400 4525);
WIRE 16 -1 (-6400 4525)(-6525 4525);
WIRE 16 -1 (-6400 4525)(-6400 4475);
WIRE 16 -1 (-6400 4475)(-6525 4475);
WIRE 16 -1 (-6400 4475)(-6400 4425);
WIRE 16 -1 (-6400 4425)(-6525 4425);
WIRE 16 -1 (-6400 4425)(-6400 4375);
WIRE 16 -1 (-6525 4375)(-6400 4375);
WIRE 16 -1 (-6400 4375)(-6400 4325);
WIRE 16 -1 (-6525 4325)(-6400 4325);
WIRE 16 -1 (-6400 4325)(-6400 4275);
WIRE 16 -1 (-6400 4275)(-6525 4275);
WIRE 16 -1 (-6400 4275)(-6400 4225);
WIRE 16 -1 (-6400 4225)(-6525 4225);
WIRE 16 -1 (-6400 4225)(-6400 4175);
WIRE 16 -1 (-6400 4175)(-6525 4175);
WIRE 16 -1 (-6400 4175)(-6400 4125);
WIRE 16 -1 (-6400 4125)(-6525 4125);
WIRE 16 -1 (-6400 4125)(-6400 4075);
WIRE 16 -1 (-6400 4075)(-6525 4075);
WIRE 16 -1 (-6400 4075)(-6400 4025);
WIRE 16 -1 (-6400 4025)(-6525 4025);
WIRE 16 -1 (-6400 4025)(-6400 3975);
WIRE 16 -1 (-6525 3975)(-6400 3975);
WIRE 16 -1 (-6400 3975)(-6400 3925);
WIRE 16 -1 (-6525 3925)(-6400 3925);
WIRE 16 -1 (-6400 3925)(-6400 3875);
WIRE 16 -1 (-6400 3875)(-6525 3875);
WIRE 16 -1 (-6400 3875)(-6400 3825);
WIRE 16 -1 (-6400 3825)(-6525 3825);
WIRE 16 -1 (-6400 3825)(-6400 3775);
WIRE 16 -1 (-6400 3775)(-6525 3775);
WIRE 16 -1 (-6400 3775)(-6400 3725);
WIRE 16 -1 (-6400 3725)(-6525 3725);
WIRE 16 -1 (-6400 3725)(-6400 3675);
WIRE 16 -1 (-6400 3675)(-6525 3675);
WIRE 16 -1 (-6400 3675)(-6400 3625);
WIRE 16 -1 (-6400 3625)(-6525 3625);
WIRE 16 -1 (-6400 3625)(-6400 3575);
WIRE 16 -1 (-6525 3575)(-6400 3575);
WIRE 16 -1 (-6400 3575)(-6400 3525);
WIRE 16 -1 (-6525 3525)(-6400 3525);
WIRE 16 -1 (-6400 3525)(-6400 3475);
WIRE 16 -1 (-6400 3475)(-6525 3475);
WIRE 16 -1 (-6400 3475)(-6400 3425);
WIRE 16 -1 (-6400 3425)(-6525 3425);
WIRE 16 -1 (-6400 3425)(-6400 3375);
WIRE 16 -1 (-6400 3375)(-6525 3375);
WIRE 16 -1 (-6400 3375)(-6400 3325);
WIRE 16 -1 (-6400 3325)(-6525 3325);
WIRE 16 -1 (-6400 3325)(-6400 3275);
WIRE 16 -1 (-6400 3275)(-6525 3275);
WIRE 16 -1 (-6400 3275)(-6400 3225);
WIRE 16 -1 (-6400 3225)(-6525 3225);
WIRE 16 -1 (-6400 3225)(-6400 3175);
WIRE 16 -1 (-6525 3175)(-6400 3175);
WIRE 16 -1 (-6400 3175)(-6400 3125);
WIRE 16 -1 (-6525 3125)(-6400 3125);
WIRE 16 -1 (-6400 3125)(-6400 3075);
WIRE 16 -1 (-6400 3075)(-6525 3075);
WIRE 16 -1 (-6400 3075)(-6400 3025);
WIRE 16 -1 (-6400 3025)(-6525 3025);
WIRE 16 -1 (-6400 3025)(-6400 2975);
WIRE 16 -1 (-6400 2975)(-6525 2975);
WIRE 16 -1 (-6400 2975)(-6400 2925);
WIRE 16 -1 (-6400 2925)(-6525 2925);
WIRE 16 -1 (-6400 2925)(-6400 2875);
WIRE 16 -1 (-6400 2875)(-6525 2875);
WIRE 16 -1 (-6400 2875)(-6400 2825);
WIRE 16 -1 (-6400 2825)(-6525 2825);
WIRE 16 -1 (-6400 2825)(-6400 2775);
WIRE 16 -1 (-6525 2775)(-6400 2775);
WIRE 16 -1 (-6400 2775)(-6400 2725);
WIRE 16 -1 (-6525 2725)(-6400 2725);
WIRE 16 -1 (-6400 2725)(-6400 2675);
WIRE 16 -1 (-6400 2675)(-6525 2675);
WIRE 16 -1 (-6400 2675)(-6400 2625);
WIRE 16 -1 (-6400 2625)(-6525 2625);
WIRE 16 -1 (-6400 2625)(-6400 2575);
WIRE 16 -1 (-6400 2575)(-6525 2575);
WIRE 16 -1 (-6400 2575)(-6400 2525);
WIRE 16 -1 (-6400 2525)(-6525 2525);
WIRE 16 -1 (-6400 2525)(-6400 2475);
WIRE 16 -1 (-6400 2475)(-6525 2475);
WIRE 16 -1 (-6400 2475)(-6400 2425);
WIRE 16 -1 (-6400 2425)(-6525 2425);
WIRE 16 -1 (-6400 2425)(-6400 2375);
WIRE 16 -1 (-6525 2375)(-6400 2375);
WIRE 16 -1 (-6400 2375)(-6400 2325);
WIRE 16 -1 (-6525 2325)(-6400 2325);
WIRE 16 -1 (-6400 2325)(-6400 2275);
WIRE 16 -1 (-6400 2275)(-6525 2275);
WIRE 16 -1 (-6400 2275)(-6400 2225);
WIRE 16 -1 (-6400 2225)(-6525 2225);
WIRE 16 -1 (-6400 2225)(-6400 2175);
WIRE 16 -1 (-6400 2175)(-6525 2175);
WIRE 16 -1 (-6400 2175)(-6400 2125);
WIRE 16 -1 (-6400 2125)(-6525 2125);
WIRE 16 -1 (-6400 2125)(-6400 2075);
WIRE 16 -1 (-6400 2075)(-6525 2075);
WIRE 16 -1 (-6400 2075)(-6400 2025);
WIRE 16 -1 (-6400 2025)(-6525 2025);
WIRE 16 -1 (-6400 2025)(-6400 1975);
WIRE 16 -1 (-6525 1975)(-6400 1975);
WIRE 16 -1 (-6400 1975)(-6400 1925);
WIRE 16 -1 (-6525 1925)(-6400 1925);
WIRE 16 -1 (-6400 1925)(-6400 1875);
WIRE 16 -1 (-6400 1875)(-6525 1875);
WIRE 16 -1 (-6400 1875)(-6400 1825);
WIRE 16 -1 (-6400 1825)(-6525 1825);
WIRE 16 -1 (-6400 1825)(-6400 1775);
WIRE 16 -1 (-6400 1775)(-6525 1775);
WIRE 16 -1 (-6400 1775)(-6400 1725);
WIRE 16 -1 (-6400 1725)(-6525 1725);
WIRE 16 -1 (-6400 1725)(-6400 1675);
WIRE 16 -1 (-6400 1675)(-6525 1675);
WIRE 16 -1 (-6400 1675)(-6400 1625);
WIRE 16 -1 (-6400 1625)(-6525 1625);
WIRE 16 -1 (-6400 1625)(-6400 1575);
WIRE 16 -1 (-6525 1575)(-6400 1575);
WIRE 16 -1 (-6400 1575)(-6400 1525);
WIRE 16 -1 (-6525 1525)(-6400 1525);
WIRE 16 -1 (-6400 1525)(-6400 1475);
WIRE 16 -1 (-6400 1475)(-6525 1475);
WIRE 16 -1 (-6400 1475)(-6400 1425);
WIRE 16 -1 (-6400 1425)(-6525 1425);
WIRE 16 -1 (-6400 1425)(-6400 1375);
WIRE 16 -1 (-6400 1375)(-6525 1375);
WIRE 16 -1 (-6400 1375)(-6400 1325);
WIRE 16 -1 (-6400 1325)(-6525 1325);
WIRE 16 -1 (-6400 1325)(-6400 1275);
WIRE 16 -1 (-6400 1275)(-6525 1275);
WIRE 16 -1 (-6400 1275)(-6400 1225);
WIRE 16 -1 (-6400 1225)(-6525 1225);
WIRE 16 -1 (-6400 1225)(-6400 1175);
WIRE 16 -1 (-6525 1175)(-6400 1175);
WIRE 16 -1 (-6400 1175)(-6400 1125);
WIRE 16 -1 (-6525 1125)(-6400 1125);
WIRE 16 -1 (-6400 1125)(-6400 1075);
WIRE 16 -1 (-6400 1075)(-6525 1075);
WIRE 16 -1 (-6400 1075)(-6400 1025);
WIRE 16 -1 (-6400 1025)(-6525 1025);
WIRE 16 -1 (-6400 1025)(-6400 975);
WIRE 16 -1 (-6400 975)(-6525 975);
WIRE 16 -1 (-6400 975)(-6400 925);
WIRE 16 -1 (-6400 925)(-6525 925);
WIRE 16 -1 (-6400 925)(-6400 875);
WIRE 16 -1 (-6400 875)(-6525 875);
WIRE 16 -1 (-6400 875)(-6400 825);
WIRE 16 -1 (-6400 825)(-6525 825);
WIRE 16 -1 (-6400 825)(-6400 775);
WIRE 16 -1 (-6525 775)(-6400 775);
WIRE 16 -1 (-6400 775)(-6400 725);
WIRE 16 -1 (-6525 725)(-6400 725);
WIRE 16 -1 (-6400 725)(-6400 675);
WIRE 16 -1 (-6400 675)(-6525 675);
WIRE 16 -1 (-6400 675)(-6400 625);
WIRE 16 -1 (-6400 625)(-6525 625);
WIRE 16 -1 (-6400 625)(-6400 575);
WIRE 16 -1 (-6400 575)(-6525 575);
WIRE 16 -1 (-6400 575)(-6400 525);
WIRE 16 -1 (-6400 525)(-6525 525);
WIRE 16 -1 (-6400 525)(-6400 475);
WIRE 16 -1 (-6400 475)(-6525 475);
WIRE 16 -1 (-6400 475)(-6400 450);
WIRE 16 -1 (-6275 6300)(-6150 6300);
WIRE 16 -1 (-6275 6300)(-6275 6250);
WIRE 16 -1 (-6275 6250)(-6150 6250);
WIRE 16 -1 (-6275 6250)(-6275 6200);
WIRE 16 -1 (-6275 6200)(-6150 6200);
WIRE 16 -1 (-6275 6200)(-6275 6150);
WIRE 16 -1 (-6275 6150)(-6150 6150);
WIRE 16 -1 (-6275 6150)(-6275 6100);
WIRE 16 -1 (-6275 6100)(-6150 6100);
WIRE 16 -1 (-6275 6100)(-6275 6050);
WIRE 16 -1 (-6150 6050)(-6275 6050);
WIRE 16 -1 (-6275 6050)(-6275 6000);
WIRE 16 -1 (-6150 6000)(-6275 6000);
WIRE 16 -1 (-6275 6000)(-6275 5950);
WIRE 16 -1 (-6275 5950)(-6150 5950);
WIRE 16 -1 (-6275 5950)(-6275 5900);
WIRE 16 -1 (-6275 5900)(-6150 5900);
WIRE 16 -1 (-6275 5900)(-6275 5850);
WIRE 16 -1 (-6275 5850)(-6150 5850);
WIRE 16 -1 (-6275 5850)(-6275 5800);
WIRE 16 -1 (-6275 5800)(-6150 5800);
WIRE 16 -1 (-6275 5800)(-6275 5750);
WIRE 16 -1 (-6275 5750)(-6150 5750);
WIRE 16 -1 (-6275 5750)(-6275 5700);
WIRE 16 -1 (-6275 5700)(-6150 5700);
WIRE 16 -1 (-6275 5700)(-6275 5650);
WIRE 16 -1 (-6150 5650)(-6275 5650);
WIRE 16 -1 (-6275 5650)(-6275 5600);
WIRE 16 -1 (-6150 5600)(-6275 5600);
WIRE 16 -1 (-6275 5600)(-6275 5550);
WIRE 16 -1 (-6275 5550)(-6150 5550);
WIRE 16 -1 (-6275 5550)(-6275 5500);
WIRE 16 -1 (-6275 5500)(-6150 5500);
WIRE 16 -1 (-6275 5500)(-6275 5450);
WIRE 16 -1 (-6275 5450)(-6150 5450);
WIRE 16 -1 (-6275 5450)(-6275 5400);
WIRE 16 -1 (-6275 5400)(-6150 5400);
WIRE 16 -1 (-6275 5400)(-6275 5350);
WIRE 16 -1 (-6275 5350)(-6150 5350);
WIRE 16 -1 (-6275 5350)(-6275 5300);
WIRE 16 -1 (-6275 5300)(-6150 5300);
WIRE 16 -1 (-6275 5300)(-6275 5250);
WIRE 16 -1 (-6150 5250)(-6275 5250);
WIRE 16 -1 (-6275 5250)(-6275 5200);
WIRE 16 -1 (-6150 5200)(-6275 5200);
WIRE 16 -1 (-6275 5200)(-6275 5150);
WIRE 16 -1 (-6275 5150)(-6150 5150);
WIRE 16 -1 (-6275 5150)(-6275 5100);
WIRE 16 -1 (-6275 5100)(-6150 5100);
WIRE 16 -1 (-6275 5100)(-6275 5050);
WIRE 16 -1 (-6275 5050)(-6150 5050);
WIRE 16 -1 (-6275 5050)(-6275 5000);
WIRE 16 -1 (-6275 5000)(-6150 5000);
WIRE 16 -1 (-6275 5000)(-6275 4950);
WIRE 16 -1 (-6275 4950)(-6150 4950);
WIRE 16 -1 (-6275 4950)(-6275 4900);
WIRE 16 -1 (-6275 4900)(-6150 4900);
WIRE 16 -1 (-6275 4900)(-6275 4850);
WIRE 16 -1 (-6150 4850)(-6275 4850);
WIRE 16 -1 (-6275 4850)(-6275 4800);
WIRE 16 -1 (-6150 4800)(-6275 4800);
WIRE 16 -1 (-6275 4800)(-6275 4750);
WIRE 16 -1 (-6275 4750)(-6150 4750);
WIRE 16 -1 (-6275 4750)(-6275 4700);
WIRE 16 -1 (-6275 4700)(-6150 4700);
WIRE 16 -1 (-6275 4700)(-6275 4650);
WIRE 16 -1 (-6275 4650)(-6150 4650);
WIRE 16 -1 (-6275 4650)(-6275 4600);
WIRE 16 -1 (-6275 4600)(-6150 4600);
WIRE 16 -1 (-6275 4600)(-6275 4550);
WIRE 16 -1 (-6275 4550)(-6150 4550);
WIRE 16 -1 (-6275 4550)(-6275 4500);
WIRE 16 -1 (-6275 4500)(-6150 4500);
WIRE 16 -1 (-6275 4500)(-6275 4450);
WIRE 16 -1 (-6150 4450)(-6275 4450);
WIRE 16 -1 (-6275 4450)(-6275 4400);
WIRE 16 -1 (-6150 4400)(-6275 4400);
WIRE 16 -1 (-6275 4400)(-6275 4350);
WIRE 16 -1 (-6275 4350)(-6150 4350);
WIRE 16 -1 (-6275 4350)(-6275 4300);
WIRE 16 -1 (-6275 4300)(-6150 4300);
WIRE 16 -1 (-6275 4300)(-6275 4250);
WIRE 16 -1 (-6275 4250)(-6150 4250);
WIRE 16 -1 (-6275 4250)(-6275 4200);
WIRE 16 -1 (-6275 4200)(-6150 4200);
WIRE 16 -1 (-6275 4200)(-6275 4150);
WIRE 16 -1 (-6275 4150)(-6150 4150);
WIRE 16 -1 (-6275 4150)(-6275 4100);
WIRE 16 -1 (-6275 4100)(-6150 4100);
WIRE 16 -1 (-6275 4100)(-6275 4050);
WIRE 16 -1 (-6150 4050)(-6275 4050);
WIRE 16 -1 (-6275 4050)(-6275 4000);
WIRE 16 -1 (-6150 4000)(-6275 4000);
WIRE 16 -1 (-6275 4000)(-6275 3950);
WIRE 16 -1 (-6275 3950)(-6150 3950);
WIRE 16 -1 (-6275 3950)(-6275 3900);
WIRE 16 -1 (-6275 3900)(-6150 3900);
WIRE 16 -1 (-6275 3900)(-6275 3850);
WIRE 16 -1 (-6275 3850)(-6150 3850);
WIRE 16 -1 (-6275 3850)(-6275 3800);
WIRE 16 -1 (-6275 3800)(-6150 3800);
WIRE 16 -1 (-6275 3800)(-6275 3750);
WIRE 16 -1 (-6275 3750)(-6150 3750);
WIRE 16 -1 (-6275 3750)(-6275 3700);
WIRE 16 -1 (-6275 3700)(-6150 3700);
WIRE 16 -1 (-6275 3700)(-6275 3650);
WIRE 16 -1 (-6150 3650)(-6275 3650);
WIRE 16 -1 (-6275 3650)(-6275 3600);
WIRE 16 -1 (-6150 3600)(-6275 3600);
WIRE 16 -1 (-6275 3600)(-6275 3550);
WIRE 16 -1 (-6275 3550)(-6150 3550);
WIRE 16 -1 (-6275 3550)(-6275 3500);
WIRE 16 -1 (-6275 3500)(-6150 3500);
WIRE 16 -1 (-6275 3500)(-6275 3450);
WIRE 16 -1 (-6275 3450)(-6150 3450);
WIRE 16 -1 (-6275 3450)(-6275 3400);
WIRE 16 -1 (-6275 3400)(-6150 3400);
WIRE 16 -1 (-6275 3400)(-6275 3350);
WIRE 16 -1 (-6275 3350)(-6150 3350);
WIRE 16 -1 (-6275 3350)(-6275 3300);
WIRE 16 -1 (-6275 3300)(-6150 3300);
WIRE 16 -1 (-6275 3300)(-6275 3250);
WIRE 16 -1 (-6150 3250)(-6275 3250);
WIRE 16 -1 (-6275 3250)(-6275 3200);
WIRE 16 -1 (-6150 3200)(-6275 3200);
WIRE 16 -1 (-6275 3200)(-6275 3150);
WIRE 16 -1 (-6275 3150)(-6150 3150);
WIRE 16 -1 (-6275 3150)(-6275 3100);
WIRE 16 -1 (-6275 3100)(-6150 3100);
WIRE 16 -1 (-6275 3100)(-6275 3050);
WIRE 16 -1 (-6275 3050)(-6150 3050);
WIRE 16 -1 (-6275 3050)(-6275 3000);
WIRE 16 -1 (-6275 3000)(-6150 3000);
WIRE 16 -1 (-6275 3000)(-6275 2950);
WIRE 16 -1 (-6275 2950)(-6150 2950);
WIRE 16 -1 (-6275 2950)(-6275 2900);
WIRE 16 -1 (-6275 2900)(-6150 2900);
WIRE 16 -1 (-6275 2900)(-6275 2850);
WIRE 16 -1 (-6150 2850)(-6275 2850);
WIRE 16 -1 (-6275 2850)(-6275 2800);
WIRE 16 -1 (-6150 2800)(-6275 2800);
WIRE 16 -1 (-6275 2800)(-6275 2750);
WIRE 16 -1 (-6275 2750)(-6150 2750);
WIRE 16 -1 (-6275 2750)(-6275 2700);
WIRE 16 -1 (-6275 2700)(-6150 2700);
WIRE 16 -1 (-6275 2700)(-6275 2650);
WIRE 16 -1 (-6275 2650)(-6150 2650);
WIRE 16 -1 (-6275 2650)(-6275 2600);
WIRE 16 -1 (-6275 2600)(-6150 2600);
WIRE 16 -1 (-6275 2600)(-6275 2550);
WIRE 16 -1 (-6275 2550)(-6150 2550);
WIRE 16 -1 (-6275 2550)(-6275 2500);
WIRE 16 -1 (-6275 2500)(-6150 2500);
WIRE 16 -1 (-6275 2500)(-6275 2450);
WIRE 16 -1 (-6150 2450)(-6275 2450);
WIRE 16 -1 (-6275 2450)(-6275 2400);
WIRE 16 -1 (-6150 2400)(-6275 2400);
WIRE 16 -1 (-6275 2400)(-6275 2350);
WIRE 16 -1 (-6275 2350)(-6150 2350);
WIRE 16 -1 (-6275 2350)(-6275 2300);
WIRE 16 -1 (-6275 2300)(-6150 2300);
WIRE 16 -1 (-6275 2300)(-6275 2250);
WIRE 16 -1 (-6275 2250)(-6150 2250);
WIRE 16 -1 (-6275 2250)(-6275 2200);
WIRE 16 -1 (-6275 2200)(-6150 2200);
WIRE 16 -1 (-6275 2200)(-6275 2150);
WIRE 16 -1 (-6275 2150)(-6150 2150);
WIRE 16 -1 (-6275 2150)(-6275 2100);
WIRE 16 -1 (-6275 2100)(-6150 2100);
WIRE 16 -1 (-6275 2100)(-6275 2050);
WIRE 16 -1 (-6150 2050)(-6275 2050);
WIRE 16 -1 (-6275 2050)(-6275 2000);
WIRE 16 -1 (-6150 2000)(-6275 2000);
WIRE 16 -1 (-6275 2000)(-6275 1950);
WIRE 16 -1 (-6275 1950)(-6150 1950);
WIRE 16 -1 (-6275 1950)(-6275 1900);
WIRE 16 -1 (-6275 1900)(-6150 1900);
WIRE 16 -1 (-6275 1900)(-6275 1850);
WIRE 16 -1 (-6275 1850)(-6150 1850);
WIRE 16 -1 (-6275 1850)(-6275 1800);
WIRE 16 -1 (-6275 1800)(-6150 1800);
WIRE 16 -1 (-6275 1800)(-6275 1750);
WIRE 16 -1 (-6275 1750)(-6150 1750);
WIRE 16 -1 (-6275 1750)(-6275 1700);
WIRE 16 -1 (-6275 1700)(-6150 1700);
WIRE 16 -1 (-6275 1700)(-6275 1650);
WIRE 16 -1 (-6150 1650)(-6275 1650);
WIRE 16 -1 (-6275 1650)(-6275 1600);
WIRE 16 -1 (-6150 1600)(-6275 1600);
WIRE 16 -1 (-6275 1600)(-6275 1550);
WIRE 16 -1 (-6275 1550)(-6150 1550);
WIRE 16 -1 (-6275 1550)(-6275 1500);
WIRE 16 -1 (-6275 1500)(-6150 1500);
WIRE 16 -1 (-6275 1500)(-6275 1450);
WIRE 16 -1 (-6275 1450)(-6150 1450);
WIRE 16 -1 (-6275 1450)(-6275 1400);
WIRE 16 -1 (-6275 1400)(-6150 1400);
WIRE 16 -1 (-6275 1400)(-6275 1350);
WIRE 16 -1 (-6275 1350)(-6150 1350);
WIRE 16 -1 (-6275 1350)(-6275 1300);
WIRE 16 -1 (-6275 1300)(-6150 1300);
WIRE 16 -1 (-6275 1300)(-6275 1250);
WIRE 16 -1 (-6150 1250)(-6275 1250);
WIRE 16 -1 (-6275 1250)(-6275 1200);
WIRE 16 -1 (-6150 1200)(-6275 1200);
WIRE 16 -1 (-6275 1200)(-6275 1150);
WIRE 16 -1 (-6275 1150)(-6150 1150);
WIRE 16 -1 (-6275 1150)(-6275 1100);
WIRE 16 -1 (-6275 1100)(-6150 1100);
WIRE 16 -1 (-6275 1100)(-6275 1050);
WIRE 16 -1 (-6275 1050)(-6150 1050);
WIRE 16 -1 (-6275 1050)(-6275 1000);
WIRE 16 -1 (-6275 1000)(-6150 1000);
WIRE 16 -1 (-6275 1000)(-6275 950);
WIRE 16 -1 (-6275 950)(-6150 950);
WIRE 16 -1 (-6275 950)(-6275 900);
WIRE 16 -1 (-6275 900)(-6150 900);
WIRE 16 -1 (-6275 900)(-6275 850);
WIRE 16 -1 (-6150 850)(-6275 850);
WIRE 16 -1 (-6275 850)(-6275 800);
WIRE 16 -1 (-6150 800)(-6275 800);
WIRE 16 -1 (-6275 800)(-6275 750);
WIRE 16 -1 (-6150 750)(-6275 750);
WIRE 16 -1 (-6275 750)(-6275 700);
WIRE 16 -1 (-6150 700)(-6275 700);
WIRE 16 -1 (-6275 700)(-6275 650);
WIRE 16 -1 (-6150 650)(-6275 650);
WIRE 16 -1 (-6275 650)(-6275 600);
WIRE 16 -1 (-6150 600)(-6275 600);
WIRE 16 -1 (-6275 600)(-6275 550);
WIRE 16 -1 (-6150 550)(-6275 550);
WIRE 16 -1 (-6275 550)(-6275 500);
WIRE 16 -1 (-6150 500)(-6275 500);
WIRE 16 -1 (-6275 500)(-6275 450);
WIRE 16 -1 (-5050 6300)(-4925 6300);
WIRE 16 -1 (-4925 6300)(-4925 6250);
WIRE 16 -1 (-4925 6250)(-4925 6200);
WIRE 16 -1 (-5050 6250)(-4925 6250);
WIRE 16 -1 (-4925 6200)(-4925 6150);
WIRE 16 -1 (-5050 6200)(-4925 6200);
WIRE 16 -1 (-5050 6150)(-4925 6150);
WIRE 16 -1 (-4925 6150)(-4925 6100);
WIRE 16 -1 (-4925 6100)(-4925 6050);
WIRE 16 -1 (-5050 6100)(-4925 6100);
WIRE 16 -1 (-4925 6050)(-4925 6000);
WIRE 16 -1 (-5050 6050)(-4925 6050);
WIRE 16 -1 (-4925 6000)(-4925 5950);
WIRE 16 -1 (-5050 6000)(-4925 6000);
WIRE 16 -1 (-4925 5950)(-4925 5900);
WIRE 16 -1 (-4925 5950)(-5050 5950);
WIRE 16 -1 (-4925 5900)(-5050 5900);
WIRE 16 -1 (-4925 5900)(-4925 5850);
WIRE 16 -1 (-4925 5850)(-4925 5800);
WIRE 16 -1 (-4925 5850)(-5050 5850);
WIRE 16 -1 (-4925 5800)(-4925 5750);
WIRE 16 -1 (-4925 5800)(-5050 5800);
WIRE 16 -1 (-4925 5750)(-4925 5700);
WIRE 16 -1 (-4925 5750)(-5050 5750);
WIRE 16 -1 (-4925 5700)(-4925 5650);
WIRE 16 -1 (-4925 5700)(-5050 5700);
WIRE 16 -1 (-5050 5650)(-4925 5650);
WIRE 16 -1 (-4925 5650)(-4925 5600);
WIRE 16 -1 (-4925 5600)(-4925 5550);
WIRE 16 -1 (-5050 5600)(-4925 5600);
WIRE 16 -1 (-4925 5550)(-4925 5500);
WIRE 16 -1 (-4925 5550)(-5050 5550);
WIRE 16 -1 (-4925 5500)(-4925 5450);
WIRE 16 -1 (-4925 5500)(-5050 5500);
WIRE 16 -1 (-4925 5450)(-4925 5400);
WIRE 16 -1 (-4925 5450)(-5050 5450);
WIRE 16 -1 (-4925 5400)(-5050 5400);
WIRE 16 -1 (-4925 5400)(-4925 5350);
WIRE 16 -1 (-4925 5350)(-4925 5300);
WIRE 16 -1 (-4925 5350)(-5050 5350);
WIRE 16 -1 (-4925 5300)(-4925 5250);
WIRE 16 -1 (-4925 5300)(-5050 5300);
WIRE 16 -1 (-4925 5250)(-4925 5200);
WIRE 16 -1 (-5050 5250)(-4925 5250);
WIRE 16 -1 (-4925 5200)(-4925 5150);
WIRE 16 -1 (-5050 5200)(-4925 5200);
WIRE 16 -1 (-4925 5150)(-5050 5150);
WIRE 16 -1 (-4925 5150)(-4925 5100);
WIRE 16 -1 (-4925 5100)(-4925 5050);
WIRE 16 -1 (-4925 5100)(-5050 5100);
WIRE 16 -1 (-4925 5050)(-4925 5000);
WIRE 16 -1 (-4925 5050)(-5050 5050);
WIRE 16 -1 (-4925 5000)(-4925 4950);
WIRE 16 -1 (-4925 5000)(-5050 5000);
WIRE 16 -1 (-4925 4950)(-4925 4900);
WIRE 16 -1 (-4925 4950)(-5050 4950);
WIRE 16 -1 (-4925 4900)(-5050 4900);
WIRE 16 -1 (-4925 4900)(-4925 4850);
WIRE 16 -1 (-4925 4850)(-4925 4800);
WIRE 16 -1 (-5050 4850)(-4925 4850);
WIRE 16 -1 (-4925 4800)(-4925 4750);
WIRE 16 -1 (-5050 4800)(-4925 4800);
WIRE 16 -1 (-4925 4750)(-4925 4700);
WIRE 16 -1 (-4925 4750)(-5050 4750);
WIRE 16 -1 (-4925 4700)(-4925 4650);
WIRE 16 -1 (-4925 4700)(-5050 4700);
WIRE 16 -1 (-4925 4650)(-5050 4650);
WIRE 16 -1 (-4925 4650)(-4925 4600);
WIRE 16 -1 (-4925 4600)(-4925 4550);
WIRE 16 -1 (-4925 4600)(-5050 4600);
WIRE 16 -1 (-4925 4550)(-4925 4500);
WIRE 16 -1 (-4925 4550)(-5050 4550);
WIRE 16 -1 (-4925 4500)(-4925 4450);
WIRE 16 -1 (-4925 4500)(-5050 4500);
WIRE 16 -1 (-4925 4450)(-4925 4400);
WIRE 16 -1 (-5050 4450)(-4925 4450);
WIRE 16 -1 (-5050 4400)(-4925 4400);
WIRE 16 -1 (-4925 4400)(-4925 4350);
WIRE 16 -1 (-4925 4350)(-4925 4300);
WIRE 16 -1 (-4925 4350)(-5050 4350);
WIRE 16 -1 (-4925 4300)(-4925 4250);
WIRE 16 -1 (-4925 4300)(-5050 4300);
WIRE 16 -1 (-4925 4250)(-4925 4200);
WIRE 16 -1 (-4925 4250)(-5050 4250);
WIRE 16 -1 (-4925 4200)(-4925 4150);
WIRE 16 -1 (-4925 4200)(-5050 4200);
WIRE 16 -1 (-4925 4150)(-4925 4100);
WIRE 16 -1 (-4925 4150)(-5050 4150);
WIRE 16 -1 (-4925 4100)(-5050 4100);
WIRE 16 -1 (-4925 4100)(-4925 4050);
WIRE 16 -1 (-4925 4050)(-4925 4000);
WIRE 16 -1 (-5050 4050)(-4925 4050);
WIRE 16 -1 (-4925 4000)(-4925 3950);
WIRE 16 -1 (-5050 4000)(-4925 4000);
WIRE 16 -1 (-4925 3950)(-4925 3900);
WIRE 16 -1 (-4925 3950)(-5050 3950);
WIRE 16 -1 (-4925 3900)(-4925 3850);
WIRE 16 -1 (-4925 3900)(-5050 3900);
WIRE 16 -1 (-4925 3850)(-5050 3850);
WIRE 16 -1 (-4925 3850)(-4925 3800);
WIRE 16 -1 (-4925 3800)(-4925 3750);
WIRE 16 -1 (-4925 3800)(-5050 3800);
WIRE 16 -1 (-4925 3750)(-4925 3700);
WIRE 16 -1 (-4925 3750)(-5050 3750);
WIRE 16 -1 (-4925 3700)(-4925 3650);
WIRE 16 -1 (-4925 3700)(-5050 3700);
WIRE 16 -1 (-4925 3650)(-4925 3600);
WIRE 16 -1 (-5050 3650)(-4925 3650);
WIRE 16 -1 (-5050 3600)(-4925 3600);
WIRE 16 -1 (-4925 3600)(-4925 3550);
WIRE 16 -1 (-4925 3550)(-4925 3500);
WIRE 16 -1 (-4925 3550)(-5050 3550);
WIRE 16 -1 (-4925 3500)(-4925 3450);
WIRE 16 -1 (-4925 3500)(-5050 3500);
WIRE 16 -1 (-4925 3450)(-4925 3400);
WIRE 16 -1 (-4925 3450)(-5050 3450);
WIRE 16 -1 (-4925 3400)(-4925 3350);
WIRE 16 -1 (-4925 3400)(-5050 3400);
WIRE 16 -1 (-4925 3350)(-5050 3350);
WIRE 16 -1 (-4925 3350)(-4925 3300);
WIRE 16 -1 (-4925 3300)(-4925 3250);
WIRE 16 -1 (-4925 3300)(-5050 3300);
WIRE 16 -1 (-4925 3250)(-4925 3200);
WIRE 16 -1 (-5050 3250)(-4925 3250);
WIRE 16 -1 (-4925 3200)(-4925 3150);
WIRE 16 -1 (-5050 3200)(-4925 3200);
WIRE 16 -1 (-4925 3150)(-4925 3100);
WIRE 16 -1 (-4925 3150)(-5050 3150);
WIRE 16 -1 (-4925 3100)(-5050 3100);
WIRE 16 -1 (-4925 3100)(-4925 3050);
WIRE 16 -1 (-4925 3050)(-4925 3000);
WIRE 16 -1 (-4925 3050)(-5050 3050);
WIRE 16 -1 (-4925 3000)(-4925 2950);
WIRE 16 -1 (-4925 3000)(-5050 3000);
WIRE 16 -1 (-4925 2950)(-4925 2900);
WIRE 16 -1 (-4925 2950)(-5050 2950);
WIRE 16 -1 (-4925 2900)(-4925 2850);
WIRE 16 -1 (-4925 2900)(-5050 2900);
WIRE 16 -1 (-5050 2850)(-4925 2850);
WIRE 16 -1 (-4925 2850)(-4925 2800);
WIRE 16 -1 (-4925 2800)(-4925 2750);
WIRE 16 -1 (-5050 2800)(-4925 2800);
WIRE 16 -1 (-4925 2750)(-4925 2700);
WIRE 16 -1 (-4925 2750)(-5050 2750);
WIRE 16 -1 (-4925 2700)(-4925 2650);
WIRE 16 -1 (-4925 2700)(-5050 2700);
WIRE 16 -1 (-4925 2650)(-4925 2600);
WIRE 16 -1 (-4925 2650)(-5050 2650);
WIRE 16 -1 (-4925 2600)(-5050 2600);
WIRE 16 -1 (-4925 2600)(-4925 2550);
WIRE 16 -1 (-4925 2550)(-4925 2500);
WIRE 16 -1 (-4925 2550)(-5050 2550);
WIRE 16 -1 (-4925 2500)(-4925 2450);
WIRE 16 -1 (-4925 2500)(-5050 2500);
WIRE 16 -1 (-4925 2450)(-4925 2400);
WIRE 16 -1 (-5050 2450)(-4925 2450);
WIRE 16 -1 (-4925 2400)(-4925 2350);
WIRE 16 -1 (-5050 2400)(-4925 2400);
WIRE 16 -1 (-4925 2350)(-5050 2350);
WIRE 16 -1 (-4925 2350)(-4925 2300);
WIRE 16 -1 (-4925 2300)(-4925 2250);
WIRE 16 -1 (-4925 2300)(-5050 2300);
WIRE 16 -1 (-4925 2250)(-4925 2200);
WIRE 16 -1 (-4925 2250)(-5050 2250);
WIRE 16 -1 (-4925 2200)(-4925 2150);
WIRE 16 -1 (-4925 2200)(-5050 2200);
WIRE 16 -1 (-4925 2150)(-4925 2100);
WIRE 16 -1 (-4925 2150)(-5050 2150);
WIRE 16 -1 (-4925 2100)(-4925 2050);
WIRE 16 -1 (-4925 2100)(-5050 2100);
WIRE 16 -1 (-5050 2050)(-4925 2050);
WIRE 16 -1 (-4925 2050)(-4925 2000);
WIRE 16 -1 (-4925 2000)(-4925 1950);
WIRE 16 -1 (-5050 2000)(-4925 2000);
WIRE 16 -1 (-4925 1950)(-4925 1900);
WIRE 16 -1 (-4925 1950)(-5050 1950);
WIRE 16 -1 (-4925 1900)(-4925 1850);
WIRE 16 -1 (-4925 1900)(-5050 1900);
WIRE 16 -1 (-4925 1850)(-4925 1800);
WIRE 16 -1 (-4925 1850)(-5050 1850);
WIRE 16 -1 (-4925 1800)(-5050 1800);
WIRE 16 -1 (-4925 1800)(-4925 1750);
WIRE 16 -1 (-4925 1750)(-4925 1700);
WIRE 16 -1 (-4925 1750)(-5050 1750);
WIRE 16 -1 (-4925 1700)(-4925 1650);
WIRE 16 -1 (-4925 1700)(-5050 1700);
WIRE 16 -1 (-4925 1650)(-4925 1600);
WIRE 16 -1 (-5050 1650)(-4925 1650);
WIRE 16 -1 (-4925 1600)(-4925 1550);
WIRE 16 -1 (-5050 1600)(-4925 1600);
WIRE 16 -1 (-4925 1550)(-5050 1550);
WIRE 16 -1 (-4925 1550)(-4925 1500);
WIRE 16 -1 (-4925 1500)(-4925 1450);
WIRE 16 -1 (-4925 1500)(-5050 1500);
WIRE 16 -1 (-4925 1450)(-4925 1400);
WIRE 16 -1 (-4925 1450)(-5050 1450);
WIRE 16 -1 (-4925 1400)(-4925 1350);
WIRE 16 -1 (-4925 1400)(-5050 1400);
WIRE 16 -1 (-4925 1350)(-4925 1300);
WIRE 16 -1 (-4925 1350)(-5050 1350);
WIRE 16 -1 (-4925 1300)(-5050 1300);
WIRE 16 -1 (-4925 1300)(-4925 1250);
WIRE 16 -1 (-4925 1250)(-4925 1200);
WIRE 16 -1 (-5050 1250)(-4925 1250);
WIRE 16 -1 (-4925 1200)(-4925 1150);
WIRE 16 -1 (-5050 1200)(-4925 1200);
WIRE 16 -1 (-4925 1150)(-4925 1100);
WIRE 16 -1 (-4925 1150)(-5050 1150);
WIRE 16 -1 (-4925 1100)(-4925 1050);
WIRE 16 -1 (-4925 1100)(-5050 1100);
WIRE 16 -1 (-4925 1050)(-5050 1050);
WIRE 16 -1 (-4925 1050)(-4925 1000);
WIRE 16 -1 (-4925 1000)(-4925 950);
WIRE 16 -1 (-4925 1000)(-5050 1000);
WIRE 16 -1 (-4925 950)(-4925 900);
WIRE 16 -1 (-4925 950)(-5050 950);
WIRE 16 -1 (-4925 900)(-4925 850);
WIRE 16 -1 (-4925 900)(-5050 900);
WIRE 16 -1 (-4925 850)(-4925 800);
WIRE 16 -1 (-5050 850)(-4925 850);
WIRE 16 -1 (-5050 800)(-4925 800);
WIRE 16 -1 (-4925 800)(-4925 750);
WIRE 16 -1 (-4925 750)(-4925 700);
WIRE 16 -1 (-4925 750)(-5050 750);
WIRE 16 -1 (-4925 700)(-4925 650);
WIRE 16 -1 (-4925 700)(-5050 700);
WIRE 16 -1 (-4925 650)(-4925 600);
WIRE 16 -1 (-4925 650)(-5050 650);
WIRE 16 -1 (-4925 600)(-4925 550);
WIRE 16 -1 (-4925 600)(-5050 600);
WIRE 16 -1 (-4925 550)(-4925 525);
WIRE 16 -1 (-4925 550)(-5050 550);
WIRE 16 -1 (-4775 6375)(-4650 6375);
WIRE 16 -1 (-4775 6375)(-4775 6325);
WIRE 16 -1 (-4775 6325)(-4650 6325);
WIRE 16 -1 (-4775 6325)(-4775 6275);
WIRE 16 -1 (-4775 6275)(-4650 6275);
WIRE 16 -1 (-4775 6275)(-4775 6225);
WIRE 16 -1 (-4775 6225)(-4650 6225);
WIRE 16 -1 (-4775 6225)(-4775 6175);
WIRE 16 -1 (-4775 6175)(-4650 6175);
WIRE 16 -1 (-4775 6175)(-4775 6125);
WIRE 16 -1 (-4650 6125)(-4775 6125);
WIRE 16 -1 (-4775 6125)(-4775 6075);
WIRE 16 -1 (-4775 6075)(-4650 6075);
WIRE 16 -1 (-4775 6075)(-4775 6025);
WIRE 16 -1 (-4775 6025)(-4650 6025);
WIRE 16 -1 (-4775 6025)(-4775 5975);
WIRE 16 -1 (-4775 5975)(-4650 5975);
WIRE 16 -1 (-4775 5975)(-4775 5925);
WIRE 16 -1 (-4775 5925)(-4650 5925);
WIRE 16 -1 (-4775 5925)(-4775 5875);
WIRE 16 -1 (-4650 5875)(-4775 5875);
WIRE 16 -1 (-4775 5875)(-4775 5825);
WIRE 16 -1 (-4775 5825)(-4650 5825);
WIRE 16 -1 (-4775 5825)(-4775 5775);
WIRE 16 -1 (-4775 5775)(-4650 5775);
WIRE 16 -1 (-4775 5775)(-4775 5725);
WIRE 16 -1 (-4775 5725)(-4650 5725);
WIRE 16 -1 (-4775 5725)(-4775 5675);
WIRE 16 -1 (-4775 5675)(-4650 5675);
WIRE 16 -1 (-4775 5675)(-4775 5625);
WIRE 16 -1 (-4650 5625)(-4775 5625);
WIRE 16 -1 (-4775 5625)(-4775 5575);
WIRE 16 -1 (-4775 5575)(-4650 5575);
WIRE 16 -1 (-4775 5575)(-4775 5525);
WIRE 16 -1 (-4775 5525)(-4650 5525);
WIRE 16 -1 (-4775 5525)(-4775 5475);
WIRE 16 -1 (-4775 5475)(-4650 5475);
WIRE 16 -1 (-4775 5475)(-4775 5425);
WIRE 16 -1 (-4775 5425)(-4650 5425);
WIRE 16 -1 (-4775 5425)(-4775 5375);
WIRE 16 -1 (-4650 5375)(-4775 5375);
WIRE 16 -1 (-4775 5375)(-4775 5325);
WIRE 16 -1 (-4775 5325)(-4650 5325);
WIRE 16 -1 (-4775 5325)(-4775 5275);
WIRE 16 -1 (-4775 5275)(-4650 5275);
WIRE 16 -1 (-4775 5275)(-4775 5225);
WIRE 16 -1 (-4775 5225)(-4650 5225);
WIRE 16 -1 (-4775 5225)(-4775 5175);
WIRE 16 -1 (-4775 5175)(-4650 5175);
WIRE 16 -1 (-4775 5175)(-4775 5125);
WIRE 16 -1 (-4775 5125)(-4650 5125);
WIRE 16 -1 (-4775 5125)(-4775 5075);
WIRE 16 -1 (-4650 5075)(-4775 5075);
WIRE 16 -1 (-4775 5075)(-4775 5025);
WIRE 16 -1 (-4775 5025)(-4650 5025);
WIRE 16 -1 (-4775 5025)(-4775 4975);
WIRE 16 -1 (-4775 4975)(-4650 4975);
WIRE 16 -1 (-4775 4975)(-4775 4925);
WIRE 16 -1 (-4775 4925)(-4650 4925);
WIRE 16 -1 (-4775 4925)(-4775 4875);
WIRE 16 -1 (-4775 4875)(-4650 4875);
WIRE 16 -1 (-4775 4875)(-4775 4825);
WIRE 16 -1 (-4650 4825)(-4775 4825);
WIRE 16 -1 (-4775 4825)(-4775 4775);
WIRE 16 -1 (-4775 4775)(-4650 4775);
WIRE 16 -1 (-4775 4775)(-4775 4725);
WIRE 16 -1 (-4775 4725)(-4650 4725);
WIRE 16 -1 (-4775 4725)(-4775 4675);
WIRE 16 -1 (-4775 4675)(-4650 4675);
WIRE 16 -1 (-4775 4675)(-4775 4625);
WIRE 16 -1 (-4775 4625)(-4650 4625);
WIRE 16 -1 (-4775 4625)(-4775 4575);
WIRE 16 -1 (-4650 4575)(-4775 4575);
WIRE 16 -1 (-4775 4575)(-4775 4525);
WIRE 16 -1 (-4775 4525)(-4650 4525);
WIRE 16 -1 (-4775 4525)(-4775 4475);
WIRE 16 -1 (-4775 4475)(-4650 4475);
WIRE 16 -1 (-4775 4475)(-4775 4425);
WIRE 16 -1 (-4775 4425)(-4650 4425);
WIRE 16 -1 (-4775 4425)(-4775 4375);
WIRE 16 -1 (-4775 4375)(-4650 4375);
WIRE 16 -1 (-4775 4375)(-4775 4325);
WIRE 16 -1 (-4650 4325)(-4775 4325);
WIRE 16 -1 (-4775 4325)(-4775 4275);
WIRE 16 -1 (-4775 4275)(-4650 4275);
WIRE 16 -1 (-4775 4275)(-4775 4225);
WIRE 16 -1 (-4775 4225)(-4650 4225);
WIRE 16 -1 (-4775 4225)(-4775 4175);
WIRE 16 -1 (-4775 4175)(-4650 4175);
WIRE 16 -1 (-4775 4175)(-4775 4125);
WIRE 16 -1 (-4775 4125)(-4650 4125);
WIRE 16 -1 (-4775 4125)(-4775 4075);
WIRE 16 -1 (-4650 4075)(-4775 4075);
WIRE 16 -1 (-4775 4075)(-4775 4025);
WIRE 16 -1 (-4775 4025)(-4650 4025);
WIRE 16 -1 (-4775 4025)(-4775 3975);
WIRE 16 -1 (-4775 3975)(-4650 3975);
WIRE 16 -1 (-4775 3975)(-4775 3925);
WIRE 16 -1 (-4775 3925)(-4650 3925);
WIRE 16 -1 (-4775 3925)(-4775 3875);
WIRE 16 -1 (-4775 3875)(-4650 3875);
WIRE 16 -1 (-4775 3875)(-4775 3825);
WIRE 16 -1 (-4650 3825)(-4775 3825);
WIRE 16 -1 (-4775 3825)(-4775 3775);
WIRE 16 -1 (-4775 3775)(-4650 3775);
WIRE 16 -1 (-4775 3775)(-4775 3725);
WIRE 16 -1 (-4775 3725)(-4650 3725);
WIRE 16 -1 (-4775 3725)(-4775 3675);
WIRE 16 -1 (-4775 3675)(-4650 3675);
WIRE 16 -1 (-4775 3675)(-4775 3625);
WIRE 16 -1 (-4775 3625)(-4650 3625);
WIRE 16 -1 (-4775 3625)(-4775 3575);
WIRE 16 -1 (-4650 3575)(-4775 3575);
WIRE 16 -1 (-4775 3575)(-4775 3525);
WIRE 16 -1 (-4775 3525)(-4650 3525);
WIRE 16 -1 (-4775 3525)(-4775 3475);
WIRE 16 -1 (-4775 3475)(-4650 3475);
WIRE 16 -1 (-4775 3475)(-4775 3425);
WIRE 16 -1 (-4775 3425)(-4650 3425);
WIRE 16 -1 (-4775 3425)(-4775 3375);
WIRE 16 -1 (-4775 3375)(-4650 3375);
WIRE 16 -1 (-4775 3375)(-4775 3325);
WIRE 16 -1 (-4650 3325)(-4775 3325);
WIRE 16 -1 (-4775 3325)(-4775 3275);
WIRE 16 -1 (-4775 3275)(-4650 3275);
WIRE 16 -1 (-4775 3275)(-4775 3225);
WIRE 16 -1 (-4775 3225)(-4650 3225);
WIRE 16 -1 (-4775 3225)(-4775 3175);
WIRE 16 -1 (-4775 3175)(-4650 3175);
WIRE 16 -1 (-4775 3175)(-4775 3125);
WIRE 16 -1 (-4775 3125)(-4650 3125);
WIRE 16 -1 (-4775 3125)(-4775 3075);
WIRE 16 -1 (-4775 3075)(-4650 3075);
WIRE 16 -1 (-4775 3075)(-4775 3025);
WIRE 16 -1 (-4650 3025)(-4775 3025);
WIRE 16 -1 (-4775 3025)(-4775 2975);
WIRE 16 -1 (-4775 2975)(-4650 2975);
WIRE 16 -1 (-4775 2975)(-4775 2925);
WIRE 16 -1 (-4775 2925)(-4650 2925);
WIRE 16 -1 (-4775 2925)(-4775 2875);
WIRE 16 -1 (-4775 2875)(-4650 2875);
WIRE 16 -1 (-4775 2875)(-4775 2825);
WIRE 16 -1 (-4775 2825)(-4650 2825);
WIRE 16 -1 (-4775 2825)(-4775 2775);
WIRE 16 -1 (-4650 2775)(-4775 2775);
WIRE 16 -1 (-4775 2775)(-4775 2725);
WIRE 16 -1 (-4775 2725)(-4650 2725);
WIRE 16 -1 (-4775 2725)(-4775 2675);
WIRE 16 -1 (-4775 2675)(-4650 2675);
WIRE 16 -1 (-4775 2675)(-4775 2625);
WIRE 16 -1 (-4775 2625)(-4650 2625);
WIRE 16 -1 (-4775 2625)(-4775 2575);
WIRE 16 -1 (-4775 2575)(-4650 2575);
WIRE 16 -1 (-4775 2575)(-4775 2525);
WIRE 16 -1 (-4650 2525)(-4775 2525);
WIRE 16 -1 (-4775 2525)(-4775 2475);
WIRE 16 -1 (-4775 2475)(-4650 2475);
WIRE 16 -1 (-4775 2475)(-4775 2425);
WIRE 16 -1 (-4775 2425)(-4650 2425);
WIRE 16 -1 (-4775 2425)(-4775 2375);
WIRE 16 -1 (-4775 2375)(-4650 2375);
WIRE 16 -1 (-4775 2375)(-4775 2325);
WIRE 16 -1 (-4775 2325)(-4650 2325);
WIRE 16 -1 (-4775 2325)(-4775 2275);
WIRE 16 -1 (-4650 2275)(-4775 2275);
WIRE 16 -1 (-4775 2275)(-4775 2225);
WIRE 16 -1 (-4775 2225)(-4650 2225);
WIRE 16 -1 (-4775 2225)(-4775 2175);
WIRE 16 -1 (-4775 2175)(-4650 2175);
WIRE 16 -1 (-4775 2175)(-4775 2125);
WIRE 16 -1 (-4775 2125)(-4650 2125);
WIRE 16 -1 (-4775 2125)(-4775 2075);
WIRE 16 -1 (-4775 2075)(-4650 2075);
WIRE 16 -1 (-4775 2075)(-4775 2025);
WIRE 16 -1 (-4650 2025)(-4775 2025);
WIRE 16 -1 (-4775 2025)(-4775 1975);
WIRE 16 -1 (-4775 1975)(-4650 1975);
WIRE 16 -1 (-4775 1975)(-4775 1925);
WIRE 16 -1 (-4775 1925)(-4650 1925);
WIRE 16 -1 (-4775 1925)(-4775 1875);
WIRE 16 -1 (-4775 1875)(-4650 1875);
WIRE 16 -1 (-4775 1875)(-4775 1825);
WIRE 16 -1 (-4775 1825)(-4650 1825);
WIRE 16 -1 (-4775 1825)(-4775 1775);
WIRE 16 -1 (-4650 1775)(-4775 1775);
WIRE 16 -1 (-4775 1775)(-4775 1725);
WIRE 16 -1 (-4775 1725)(-4650 1725);
WIRE 16 -1 (-4775 1725)(-4775 1675);
WIRE 16 -1 (-4775 1675)(-4650 1675);
WIRE 16 -1 (-4775 1675)(-4775 1625);
WIRE 16 -1 (-4775 1625)(-4650 1625);
WIRE 16 -1 (-4775 1625)(-4775 1575);
WIRE 16 -1 (-4775 1575)(-4650 1575);
WIRE 16 -1 (-4775 1575)(-4775 1525);
WIRE 16 -1 (-4650 1525)(-4775 1525);
WIRE 16 -1 (-4775 1525)(-4775 1475);
WIRE 16 -1 (-4775 1475)(-4650 1475);
WIRE 16 -1 (-4775 1475)(-4775 1425);
WIRE 16 -1 (-4775 1425)(-4650 1425);
WIRE 16 -1 (-4775 1425)(-4775 1375);
WIRE 16 -1 (-4775 1375)(-4650 1375);
WIRE 16 -1 (-4775 1375)(-4775 1325);
WIRE 16 -1 (-4775 1325)(-4650 1325);
WIRE 16 -1 (-4775 1325)(-4775 1275);
WIRE 16 -1 (-4650 1275)(-4775 1275);
WIRE 16 -1 (-4775 1275)(-4775 1225);
WIRE 16 -1 (-4775 1225)(-4650 1225);
WIRE 16 -1 (-4775 1225)(-4775 1175);
WIRE 16 -1 (-4775 1175)(-4650 1175);
WIRE 16 -1 (-4775 1175)(-4775 1125);
WIRE 16 -1 (-4775 1125)(-4650 1125);
WIRE 16 -1 (-4775 1125)(-4775 1075);
WIRE 16 -1 (-4775 1075)(-4650 1075);
WIRE 16 -1 (-4775 1075)(-4775 1025);
WIRE 16 -1 (-4775 1025)(-4650 1025);
WIRE 16 -1 (-4775 1025)(-4775 975);
WIRE 16 -1 (-4650 975)(-4775 975);
WIRE 16 -1 (-4775 975)(-4775 925);
WIRE 16 -1 (-4775 925)(-4650 925);
WIRE 16 -1 (-4775 925)(-4775 875);
WIRE 16 -1 (-4775 875)(-4650 875);
WIRE 16 -1 (-4775 875)(-4775 825);
WIRE 16 -1 (-4775 825)(-4650 825);
WIRE 16 -1 (-4775 825)(-4775 775);
WIRE 16 -1 (-4775 775)(-4650 775);
WIRE 16 -1 (-4775 775)(-4775 725);
WIRE 16 -1 (-4650 725)(-4775 725);
WIRE 16 -1 (-4775 725)(-4775 675);
WIRE 16 -1 (-4775 675)(-4650 675);
WIRE 16 -1 (-4775 675)(-4775 625);
WIRE 16 -1 (-4775 625)(-4650 625);
WIRE 16 -1 (-4775 625)(-4775 575);
WIRE 16 -1 (-4775 575)(-4650 575);
WIRE 16 -1 (-4775 575)(-4775 525);
WIRE 16 -1 (-3550 6375)(-3425 6375);
WIRE 16 -1 (-3425 6375)(-3425 6325);
WIRE 16 -1 (-3425 6325)(-3425 6275);
WIRE 16 -1 (-3550 6325)(-3425 6325);
WIRE 16 -1 (-3425 6275)(-3425 6225);
WIRE 16 -1 (-3550 6275)(-3425 6275);
WIRE 16 -1 (-3425 6225)(-3425 6175);
WIRE 16 -1 (-3550 6225)(-3425 6225);
WIRE 16 -1 (-3550 6175)(-3425 6175);
WIRE 16 -1 (-3425 6175)(-3425 6125);
WIRE 16 -1 (-3425 6125)(-3425 6075);
WIRE 16 -1 (-3550 6125)(-3425 6125);
WIRE 16 -1 (-3425 6075)(-3425 6025);
WIRE 16 -1 (-3550 6075)(-3425 6075);
WIRE 16 -1 (-3425 6025)(-3425 5975);
WIRE 16 -1 (-3550 6025)(-3425 6025);
WIRE 16 -1 (-3425 5975)(-3425 5925);
WIRE 16 -1 (-3425 5975)(-3550 5975);
WIRE 16 -1 (-3425 5925)(-3550 5925);
WIRE 16 -1 (-3425 5925)(-3425 5875);
WIRE 16 -1 (-3425 5875)(-3425 5825);
WIRE 16 -1 (-3425 5875)(-3550 5875);
WIRE 16 -1 (-3425 5825)(-3425 5775);
WIRE 16 -1 (-3425 5825)(-3550 5825);
WIRE 16 -1 (-3425 5775)(-3425 5725);
WIRE 16 -1 (-3425 5775)(-3550 5775);
WIRE 16 -1 (-3425 5725)(-3425 5675);
WIRE 16 -1 (-3425 5725)(-3550 5725);
WIRE 16 -1 (-3550 5675)(-3425 5675);
WIRE 16 -1 (-3425 5675)(-3425 5625);
WIRE 16 -1 (-3425 5625)(-3425 5575);
WIRE 16 -1 (-3550 5625)(-3425 5625);
WIRE 16 -1 (-3425 5575)(-3425 5525);
WIRE 16 -1 (-3425 5575)(-3550 5575);
WIRE 16 -1 (-3425 5525)(-3425 5475);
WIRE 16 -1 (-3425 5525)(-3550 5525);
WIRE 16 -1 (-3425 5475)(-3425 5425);
WIRE 16 -1 (-3425 5475)(-3550 5475);
WIRE 16 -1 (-3425 5425)(-3550 5425);
WIRE 16 -1 (-3425 5425)(-3425 5375);
WIRE 16 -1 (-3425 5375)(-3425 5325);
WIRE 16 -1 (-3425 5375)(-3550 5375);
WIRE 16 -1 (-3425 5325)(-3425 5275);
WIRE 16 -1 (-3425 5325)(-3550 5325);
WIRE 16 -1 (-3425 5275)(-3425 5225);
WIRE 16 -1 (-3550 5275)(-3425 5275);
WIRE 16 -1 (-3425 5225)(-3425 5175);
WIRE 16 -1 (-3550 5225)(-3425 5225);
WIRE 16 -1 (-3425 5175)(-3425 5125);
WIRE 16 -1 (-3425 5175)(-3550 5175);
WIRE 16 -1 (-3425 5125)(-3550 5125);
WIRE 16 -1 (-3425 5125)(-3425 5075);
WIRE 16 -1 (-3425 5075)(-3425 5025);
WIRE 16 -1 (-3425 5075)(-3550 5075);
WIRE 16 -1 (-3425 5025)(-3425 4975);
WIRE 16 -1 (-3425 5025)(-3550 5025);
WIRE 16 -1 (-3425 4975)(-3425 4925);
WIRE 16 -1 (-3425 4975)(-3550 4975);
WIRE 16 -1 (-3425 4925)(-3425 4875);
WIRE 16 -1 (-3425 4925)(-3550 4925);
WIRE 16 -1 (-3550 4875)(-3425 4875);
WIRE 16 -1 (-3425 4875)(-3425 4825);
WIRE 16 -1 (-3425 4825)(-3425 4775);
WIRE 16 -1 (-3550 4825)(-3425 4825);
WIRE 16 -1 (-3425 4775)(-3425 4725);
WIRE 16 -1 (-3425 4775)(-3550 4775);
WIRE 16 -1 (-3425 4725)(-3425 4675);
WIRE 16 -1 (-3425 4725)(-3550 4725);
WIRE 16 -1 (-3425 4675)(-3425 4625);
WIRE 16 -1 (-3425 4675)(-3550 4675);
WIRE 16 -1 (-3425 4625)(-3550 4625);
WIRE 16 -1 (-3425 4625)(-3425 4575);
WIRE 16 -1 (-3425 4575)(-3425 4525);
WIRE 16 -1 (-3425 4575)(-3550 4575);
WIRE 16 -1 (-3425 4525)(-3425 4475);
WIRE 16 -1 (-3425 4525)(-3550 4525);
WIRE 16 -1 (-3425 4475)(-3425 4425);
WIRE 16 -1 (-3550 4475)(-3425 4475);
WIRE 16 -1 (-3425 4425)(-3425 4375);
WIRE 16 -1 (-3550 4425)(-3425 4425);
WIRE 16 -1 (-3425 4375)(-3550 4375);
WIRE 16 -1 (-3425 4375)(-3425 4325);
WIRE 16 -1 (-3425 4325)(-3425 4275);
WIRE 16 -1 (-3425 4325)(-3550 4325);
WIRE 16 -1 (-3425 4275)(-3425 4225);
WIRE 16 -1 (-3425 4275)(-3550 4275);
WIRE 16 -1 (-3425 4225)(-3425 4175);
WIRE 16 -1 (-3425 4225)(-3550 4225);
WIRE 16 -1 (-3425 4175)(-3425 4125);
WIRE 16 -1 (-3425 4175)(-3550 4175);
WIRE 16 -1 (-3425 4125)(-3550 4125);
WIRE 16 -1 (-3425 4125)(-3425 4075);
WIRE 16 -1 (-3425 4075)(-3425 4025);
WIRE 16 -1 (-3550 4075)(-3425 4075);
WIRE 16 -1 (-3425 4025)(-3425 3975);
WIRE 16 -1 (-3550 4025)(-3425 4025);
WIRE 16 -1 (-3425 3975)(-3425 3925);
WIRE 16 -1 (-3425 3975)(-3550 3975);
WIRE 16 -1 (-3425 3925)(-3425 3875);
WIRE 16 -1 (-3425 3925)(-3550 3925);
WIRE 16 -1 (-3425 3875)(-3550 3875);
WIRE 16 -1 (-3425 3875)(-3425 3825);
WIRE 16 -1 (-3425 3825)(-3425 3775);
WIRE 16 -1 (-3425 3825)(-3550 3825);
WIRE 16 -1 (-3425 3775)(-3425 3725);
WIRE 16 -1 (-3425 3775)(-3550 3775);
WIRE 16 -1 (-3425 3725)(-3425 3675);
WIRE 16 -1 (-3425 3725)(-3550 3725);
WIRE 16 -1 (-3425 3675)(-3425 3625);
WIRE 16 -1 (-3550 3675)(-3425 3675);
WIRE 16 -1 (-3550 3625)(-3425 3625);
WIRE 16 -1 (-3425 3625)(-3425 3575);
WIRE 16 -1 (-3425 3575)(-3425 3525);
WIRE 16 -1 (-3425 3575)(-3550 3575);
WIRE 16 -1 (-3425 3525)(-3425 3475);
WIRE 16 -1 (-3425 3525)(-3550 3525);
WIRE 16 -1 (-3425 3475)(-3425 3425);
WIRE 16 -1 (-3425 3475)(-3550 3475);
WIRE 16 -1 (-3425 3425)(-3425 3375);
WIRE 16 -1 (-3425 3425)(-3550 3425);
WIRE 16 -1 (-3425 3375)(-3550 3375);
WIRE 16 -1 (-3425 3375)(-3425 3325);
WIRE 16 -1 (-3425 3325)(-3425 3275);
WIRE 16 -1 (-3425 3325)(-3550 3325);
WIRE 16 -1 (-3425 3275)(-3425 3225);
WIRE 16 -1 (-3550 3275)(-3425 3275);
WIRE 16 -1 (-3425 3225)(-3425 3175);
WIRE 16 -1 (-3550 3225)(-3425 3225);
WIRE 16 -1 (-3425 3175)(-3425 3125);
WIRE 16 -1 (-3425 3175)(-3550 3175);
WIRE 16 -1 (-3425 3125)(-3425 3075);
WIRE 16 -1 (-3425 3125)(-3550 3125);
WIRE 16 -1 (-3425 3075)(-3550 3075);
WIRE 16 -1 (-3425 3075)(-3425 3025);
WIRE 16 -1 (-3425 3025)(-3425 2975);
WIRE 16 -1 (-3425 3025)(-3550 3025);
WIRE 16 -1 (-3425 2975)(-3425 2925);
WIRE 16 -1 (-3425 2975)(-3550 2975);
WIRE 16 -1 (-3425 2925)(-3425 2875);
WIRE 16 -1 (-3425 2925)(-3550 2925);
WIRE 16 -1 (-3425 2875)(-3425 2825);
WIRE 16 -1 (-3550 2875)(-3425 2875);
WIRE 16 -1 (-3550 2825)(-3425 2825);
WIRE 16 -1 (-3425 2825)(-3425 2775);
WIRE 16 -1 (-3425 2775)(-3425 2725);
WIRE 16 -1 (-3425 2775)(-3550 2775);
WIRE 16 -1 (-3425 2725)(-3425 2675);
WIRE 16 -1 (-3425 2725)(-3550 2725);
WIRE 16 -1 (-3425 2675)(-3425 2625);
WIRE 16 -1 (-3425 2675)(-3550 2675);
WIRE 16 -1 (-3425 2625)(-3425 2575);
WIRE 16 -1 (-3425 2625)(-3550 2625);
WIRE 16 -1 (-3425 2575)(-3550 2575);
WIRE 16 -1 (-3425 2575)(-3425 2525);
WIRE 16 -1 (-3425 2525)(-3425 2475);
WIRE 16 -1 (-3425 2525)(-3550 2525);
WIRE 16 -1 (-3425 2475)(-3425 2425);
WIRE 16 -1 (-3550 2475)(-3425 2475);
WIRE 16 -1 (-3425 2425)(-3425 2375);
WIRE 16 -1 (-3550 2425)(-3425 2425);
WIRE 16 -1 (-3425 2375)(-3425 2325);
WIRE 16 -1 (-3425 2375)(-3550 2375);
WIRE 16 -1 (-3425 2325)(-3550 2325);
WIRE 16 -1 (-3425 2325)(-3425 2275);
WIRE 16 -1 (-3425 2275)(-3425 2225);
WIRE 16 -1 (-3425 2275)(-3550 2275);
WIRE 16 -1 (-3425 2225)(-3425 2175);
WIRE 16 -1 (-3425 2225)(-3550 2225);
WIRE 16 -1 (-3425 2175)(-3425 2125);
WIRE 16 -1 (-3425 2175)(-3550 2175);
WIRE 16 -1 (-3425 2125)(-3425 2075);
WIRE 16 -1 (-3425 2125)(-3550 2125);
WIRE 16 -1 (-3550 2075)(-3425 2075);
WIRE 16 -1 (-3425 2075)(-3425 2025);
WIRE 16 -1 (-3425 2025)(-3425 1975);
WIRE 16 -1 (-3550 2025)(-3425 2025);
WIRE 16 -1 (-3425 1975)(-3425 1925);
WIRE 16 -1 (-3425 1975)(-3550 1975);
WIRE 16 -1 (-3425 1925)(-3425 1875);
WIRE 16 -1 (-3425 1925)(-3550 1925);
WIRE 16 -1 (-3425 1875)(-3425 1825);
WIRE 16 -1 (-3425 1875)(-3550 1875);
WIRE 16 -1 (-3425 1825)(-3550 1825);
WIRE 16 -1 (-3425 1825)(-3425 1775);
WIRE 16 -1 (-3425 1775)(-3425 1725);
WIRE 16 -1 (-3425 1775)(-3550 1775);
WIRE 16 -1 (-3425 1725)(-3425 1675);
WIRE 16 -1 (-3425 1725)(-3550 1725);
WIRE 16 -1 (-3425 1675)(-3425 1625);
WIRE 16 -1 (-3550 1675)(-3425 1675);
WIRE 16 -1 (-3425 1625)(-3425 1575);
WIRE 16 -1 (-3550 1625)(-3425 1625);
WIRE 16 -1 (-3425 1575)(-3550 1575);
WIRE 16 -1 (-3425 1575)(-3425 1525);
WIRE 16 -1 (-3425 1525)(-3425 1475);
WIRE 16 -1 (-3425 1525)(-3550 1525);
WIRE 16 -1 (-3425 1475)(-3425 1425);
WIRE 16 -1 (-3425 1475)(-3550 1475);
WIRE 16 -1 (-3425 1425)(-3425 1375);
WIRE 16 -1 (-3425 1425)(-3550 1425);
WIRE 16 -1 (-3425 1375)(-3425 1325);
WIRE 16 -1 (-3425 1375)(-3550 1375);
WIRE 16 -1 (-3425 1325)(-3550 1325);
WIRE 16 -1 (-3425 1325)(-3425 1275);
WIRE 16 -1 (-3425 1275)(-3425 1225);
WIRE 16 -1 (-3550 1275)(-3425 1275);
WIRE 16 -1 (-3425 1225)(-3425 1175);
WIRE 16 -1 (-3550 1225)(-3425 1225);
WIRE 16 -1 (-3425 1175)(-3425 1125);
WIRE 16 -1 (-3425 1175)(-3550 1175);
WIRE 16 -1 (-3425 1125)(-3425 1075);
WIRE 16 -1 (-3425 1125)(-3550 1125);
WIRE 16 -1 (-3425 1075)(-3425 1025);
WIRE 16 -1 (-3425 1075)(-3550 1075);
WIRE 16 -1 (-3425 1025)(-3550 1025);
WIRE 16 -1 (-3425 1025)(-3425 975);
WIRE 16 -1 (-3425 975)(-3425 925);
WIRE 16 -1 (-3425 975)(-3550 975);
WIRE 16 -1 (-3425 925)(-3425 875);
WIRE 16 -1 (-3425 925)(-3550 925);
WIRE 16 -1 (-3425 875)(-3425 825);
WIRE 16 -1 (-3550 875)(-3425 875);
WIRE 16 -1 (-3425 825)(-3425 775);
WIRE 16 -1 (-3550 825)(-3425 825);
WIRE 16 -1 (-3425 775)(-3550 775);
WIRE 16 -1 (-3425 775)(-3425 725);
WIRE 16 -1 (-3425 725)(-3425 675);
WIRE 16 -1 (-3425 725)(-3550 725);
WIRE 16 -1 (-3425 675)(-3425 625);
WIRE 16 -1 (-3425 675)(-3550 675);
WIRE 16 -1 (-3425 625)(-3425 575);
WIRE 16 -1 (-3425 625)(-3550 625);
WIRE 16 -1 (-3425 575)(-3425 550);
WIRE 16 -1 (-3425 575)(-3550 575);
WIRE 16 -1 (-3275 6375)(-3175 6375);
WIRE 16 -1 (-3275 6375)(-3275 6325);
WIRE 16 -1 (-3275 6325)(-3175 6325);
WIRE 16 -1 (-3275 6325)(-3275 6275);
WIRE 16 -1 (-3275 6275)(-3175 6275);
WIRE 16 -1 (-3275 6275)(-3275 6225);
WIRE 16 -1 (-3275 6225)(-3175 6225);
WIRE 16 -1 (-3275 6225)(-3275 6175);
WIRE 16 -1 (-3275 6175)(-3175 6175);
WIRE 16 -1 (-3275 6175)(-3275 6125);
WIRE 16 -1 (-3175 6125)(-3275 6125);
WIRE 16 -1 (-3275 6125)(-3275 6075);
WIRE 16 -1 (-3175 6075)(-3275 6075);
WIRE 16 -1 (-3275 6075)(-3275 6025);
WIRE 16 -1 (-3275 6025)(-3175 6025);
WIRE 16 -1 (-3275 6025)(-3275 5975);
WIRE 16 -1 (-3275 5975)(-3175 5975);
WIRE 16 -1 (-3275 5975)(-3275 5925);
WIRE 16 -1 (-3275 5925)(-3175 5925);
WIRE 16 -1 (-3275 5925)(-3275 5875);
WIRE 16 -1 (-3275 5875)(-3175 5875);
WIRE 16 -1 (-3275 5875)(-3275 5825);
WIRE 16 -1 (-3275 5825)(-3175 5825);
WIRE 16 -1 (-3275 5825)(-3275 5775);
WIRE 16 -1 (-3275 5775)(-3175 5775);
WIRE 16 -1 (-3275 5775)(-3275 5725);
WIRE 16 -1 (-3175 5725)(-3275 5725);
WIRE 16 -1 (-3275 5725)(-3275 5675);
WIRE 16 -1 (-3175 5675)(-3275 5675);
WIRE 16 -1 (-3275 5675)(-3275 5625);
WIRE 16 -1 (-3275 5625)(-3175 5625);
WIRE 16 -1 (-3275 5625)(-3275 5575);
WIRE 16 -1 (-3275 5575)(-3175 5575);
WIRE 16 -1 (-3275 5575)(-3275 5525);
WIRE 16 -1 (-3275 5525)(-3175 5525);
WIRE 16 -1 (-3275 5525)(-3275 5475);
WIRE 16 -1 (-3275 5475)(-3175 5475);
WIRE 16 -1 (-3275 5475)(-3275 5425);
WIRE 16 -1 (-3275 5425)(-3175 5425);
WIRE 16 -1 (-3275 5425)(-3275 5375);
WIRE 16 -1 (-3275 5375)(-3175 5375);
WIRE 16 -1 (-3275 5375)(-3275 5325);
WIRE 16 -1 (-3175 5325)(-3275 5325);
WIRE 16 -1 (-3275 5325)(-3275 5275);
WIRE 16 -1 (-3175 5275)(-3275 5275);
WIRE 16 -1 (-3275 5275)(-3275 5225);
WIRE 16 -1 (-3275 5225)(-3175 5225);
WIRE 16 -1 (-3275 5225)(-3275 5175);
WIRE 16 -1 (-3275 5175)(-3175 5175);
WIRE 16 -1 (-3275 5175)(-3275 5125);
WIRE 16 -1 (-3275 5125)(-3175 5125);
WIRE 16 -1 (-3275 5125)(-3275 5075);
WIRE 16 -1 (-3275 5075)(-3175 5075);
WIRE 16 -1 (-3275 5075)(-3275 5025);
WIRE 16 -1 (-3275 5025)(-3175 5025);
WIRE 16 -1 (-3275 5025)(-3275 4975);
WIRE 16 -1 (-3275 4975)(-3175 4975);
WIRE 16 -1 (-3275 4975)(-3275 4925);
WIRE 16 -1 (-3175 4925)(-3275 4925);
WIRE 16 -1 (-3275 4925)(-3275 4875);
WIRE 16 -1 (-3175 4875)(-3275 4875);
WIRE 16 -1 (-3275 4875)(-3275 4825);
WIRE 16 -1 (-3275 4825)(-3175 4825);
WIRE 16 -1 (-3275 4825)(-3275 4775);
WIRE 16 -1 (-3275 4775)(-3175 4775);
WIRE 16 -1 (-3275 4775)(-3275 4725);
WIRE 16 -1 (-3275 4725)(-3175 4725);
WIRE 16 -1 (-3275 4725)(-3275 4675);
WIRE 16 -1 (-3275 4675)(-3175 4675);
WIRE 16 -1 (-3275 4675)(-3275 4625);
WIRE 16 -1 (-3275 4625)(-3175 4625);
WIRE 16 -1 (-3275 4625)(-3275 4575);
WIRE 16 -1 (-3275 4575)(-3175 4575);
WIRE 16 -1 (-3275 4575)(-3275 4525);
WIRE 16 -1 (-3175 4525)(-3275 4525);
WIRE 16 -1 (-3275 4525)(-3275 4475);
WIRE 16 -1 (-3175 4475)(-3275 4475);
WIRE 16 -1 (-3275 4475)(-3275 4425);
WIRE 16 -1 (-3275 4425)(-3175 4425);
WIRE 16 -1 (-3275 4425)(-3275 4375);
WIRE 16 -1 (-3275 4375)(-3175 4375);
WIRE 16 -1 (-3275 4375)(-3275 4325);
WIRE 16 -1 (-3275 4325)(-3175 4325);
WIRE 16 -1 (-3275 4325)(-3275 4275);
WIRE 16 -1 (-3275 4275)(-3175 4275);
WIRE 16 -1 (-3275 4275)(-3275 4225);
WIRE 16 -1 (-3275 4225)(-3175 4225);
WIRE 16 -1 (-3275 4225)(-3275 4175);
WIRE 16 -1 (-3275 4175)(-3175 4175);
WIRE 16 -1 (-3275 4175)(-3275 4125);
WIRE 16 -1 (-3175 4125)(-3275 4125);
WIRE 16 -1 (-3275 4125)(-3275 4075);
WIRE 16 -1 (-3175 4075)(-3275 4075);
WIRE 16 -1 (-3275 4075)(-3275 4025);
WIRE 16 -1 (-3275 4025)(-3175 4025);
WIRE 16 -1 (-3275 4025)(-3275 3975);
WIRE 16 -1 (-3275 3975)(-3175 3975);
WIRE 16 -1 (-3275 3975)(-3275 3925);
WIRE 16 -1 (-3275 3925)(-3175 3925);
WIRE 16 -1 (-3275 3925)(-3275 3875);
WIRE 16 -1 (-3275 3875)(-3175 3875);
WIRE 16 -1 (-3275 3875)(-3275 3825);
WIRE 16 -1 (-3275 3825)(-3175 3825);
WIRE 16 -1 (-3275 3825)(-3275 3775);
WIRE 16 -1 (-3275 3775)(-3175 3775);
WIRE 16 -1 (-3275 3775)(-3275 3725);
WIRE 16 -1 (-3175 3725)(-3275 3725);
WIRE 16 -1 (-3275 3725)(-3275 3675);
WIRE 16 -1 (-3175 3675)(-3275 3675);
WIRE 16 -1 (-3275 3675)(-3275 3625);
WIRE 16 -1 (-3275 3625)(-3175 3625);
WIRE 16 -1 (-3275 3625)(-3275 3575);
WIRE 16 -1 (-3275 3575)(-3175 3575);
WIRE 16 -1 (-3275 3575)(-3275 3525);
WIRE 16 -1 (-3275 3525)(-3175 3525);
WIRE 16 -1 (-3275 3525)(-3275 3475);
WIRE 16 -1 (-3275 3475)(-3175 3475);
WIRE 16 -1 (-3275 3475)(-3275 3425);
WIRE 16 -1 (-3275 3425)(-3175 3425);
WIRE 16 -1 (-3275 3425)(-3275 3375);
WIRE 16 -1 (-3275 3375)(-3175 3375);
WIRE 16 -1 (-3275 3375)(-3275 3325);
WIRE 16 -1 (-3175 3325)(-3275 3325);
WIRE 16 -1 (-3275 3325)(-3275 3275);
WIRE 16 -1 (-3175 3275)(-3275 3275);
WIRE 16 -1 (-3275 3275)(-3275 3225);
WIRE 16 -1 (-3275 3225)(-3175 3225);
WIRE 16 -1 (-3275 3225)(-3275 3175);
WIRE 16 -1 (-3275 3175)(-3175 3175);
WIRE 16 -1 (-3275 3175)(-3275 3125);
WIRE 16 -1 (-3275 3125)(-3175 3125);
WIRE 16 -1 (-3275 3125)(-3275 3075);
WIRE 16 -1 (-3275 3075)(-3175 3075);
WIRE 16 -1 (-3275 3075)(-3275 3025);
WIRE 16 -1 (-3275 3025)(-3175 3025);
WIRE 16 -1 (-3275 3025)(-3275 2975);
WIRE 16 -1 (-3275 2975)(-3175 2975);
WIRE 16 -1 (-3275 2975)(-3275 2925);
WIRE 16 -1 (-3175 2925)(-3275 2925);
WIRE 16 -1 (-3275 2925)(-3275 2875);
WIRE 16 -1 (-3175 2875)(-3275 2875);
WIRE 16 -1 (-3275 2875)(-3275 2825);
WIRE 16 -1 (-3275 2825)(-3175 2825);
WIRE 16 -1 (-3275 2825)(-3275 2775);
WIRE 16 -1 (-3275 2775)(-3175 2775);
WIRE 16 -1 (-3275 2775)(-3275 2725);
WIRE 16 -1 (-3275 2725)(-3175 2725);
WIRE 16 -1 (-3275 2725)(-3275 2675);
WIRE 16 -1 (-3275 2675)(-3175 2675);
WIRE 16 -1 (-3275 2675)(-3275 2625);
WIRE 16 -1 (-3275 2625)(-3175 2625);
WIRE 16 -1 (-3275 2625)(-3275 2575);
WIRE 16 -1 (-3275 2575)(-3175 2575);
WIRE 16 -1 (-3275 2575)(-3275 2525);
WIRE 16 -1 (-3175 2525)(-3275 2525);
WIRE 16 -1 (-3275 2525)(-3275 2475);
WIRE 16 -1 (-3175 2475)(-3275 2475);
WIRE 16 -1 (-3275 2475)(-3275 2425);
WIRE 16 -1 (-3275 2425)(-3175 2425);
WIRE 16 -1 (-3275 2425)(-3275 2375);
WIRE 16 -1 (-3275 2375)(-3175 2375);
WIRE 16 -1 (-3275 2375)(-3275 2325);
WIRE 16 -1 (-3275 2325)(-3175 2325);
WIRE 16 -1 (-3275 2325)(-3275 2275);
WIRE 16 -1 (-3275 2275)(-3175 2275);
WIRE 16 -1 (-3275 2275)(-3275 2225);
WIRE 16 -1 (-3275 2225)(-3175 2225);
WIRE 16 -1 (-3275 2225)(-3275 2175);
WIRE 16 -1 (-3275 2175)(-3175 2175);
WIRE 16 -1 (-3275 2175)(-3275 2125);
WIRE 16 -1 (-3175 2125)(-3275 2125);
WIRE 16 -1 (-3275 2125)(-3275 2075);
WIRE 16 -1 (-3175 2075)(-3275 2075);
WIRE 16 -1 (-3275 2075)(-3275 2025);
WIRE 16 -1 (-3275 2025)(-3175 2025);
WIRE 16 -1 (-3275 2025)(-3275 1975);
WIRE 16 -1 (-3275 1975)(-3175 1975);
WIRE 16 -1 (-3275 1975)(-3275 1925);
WIRE 16 -1 (-3275 1925)(-3175 1925);
WIRE 16 -1 (-3275 1925)(-3275 1875);
WIRE 16 -1 (-3275 1875)(-3175 1875);
WIRE 16 -1 (-3275 1875)(-3275 1825);
WIRE 16 -1 (-3275 1825)(-3175 1825);
WIRE 16 -1 (-3275 1825)(-3275 1775);
WIRE 16 -1 (-3275 1775)(-3175 1775);
WIRE 16 -1 (-3275 1775)(-3275 1725);
WIRE 16 -1 (-3175 1725)(-3275 1725);
WIRE 16 -1 (-3275 1725)(-3275 1675);
WIRE 16 -1 (-3175 1675)(-3275 1675);
WIRE 16 -1 (-3275 1675)(-3275 1625);
WIRE 16 -1 (-3275 1625)(-3175 1625);
WIRE 16 -1 (-3275 1625)(-3275 1575);
WIRE 16 -1 (-3275 1575)(-3175 1575);
WIRE 16 -1 (-3275 1575)(-3275 1525);
WIRE 16 -1 (-3275 1525)(-3175 1525);
WIRE 16 -1 (-3275 1525)(-3275 1475);
WIRE 16 -1 (-3275 1475)(-3175 1475);
WIRE 16 -1 (-3275 1475)(-3275 1425);
WIRE 16 -1 (-3275 1425)(-3175 1425);
WIRE 16 -1 (-3275 1425)(-3275 1375);
WIRE 16 -1 (-3275 1375)(-3175 1375);
WIRE 16 -1 (-3275 1375)(-3275 1325);
WIRE 16 -1 (-3175 1325)(-3275 1325);
WIRE 16 -1 (-3275 1325)(-3275 1275);
WIRE 16 -1 (-3175 1275)(-3275 1275);
WIRE 16 -1 (-3275 1275)(-3275 1225);
WIRE 16 -1 (-3275 1225)(-3175 1225);
WIRE 16 -1 (-3275 1225)(-3275 1175);
WIRE 16 -1 (-3275 1175)(-3175 1175);
WIRE 16 -1 (-3275 1175)(-3275 1125);
WIRE 16 -1 (-3275 1125)(-3175 1125);
WIRE 16 -1 (-3275 1125)(-3275 1075);
WIRE 16 -1 (-3275 1075)(-3175 1075);
WIRE 16 -1 (-3275 1075)(-3275 1025);
WIRE 16 -1 (-3275 1025)(-3175 1025);
WIRE 16 -1 (-3275 1025)(-3275 975);
WIRE 16 -1 (-3275 975)(-3175 975);
WIRE 16 -1 (-3275 975)(-3275 925);
WIRE 16 -1 (-3175 925)(-3275 925);
WIRE 16 -1 (-3275 925)(-3275 875);
WIRE 16 -1 (-3175 875)(-3275 875);
WIRE 16 -1 (-3275 875)(-3275 825);
WIRE 16 -1 (-3175 825)(-3275 825);
WIRE 16 -1 (-3275 825)(-3275 775);
WIRE 16 -1 (-3175 775)(-3275 775);
WIRE 16 -1 (-3275 775)(-3275 725);
WIRE 16 -1 (-3175 725)(-3275 725);
WIRE 16 -1 (-3275 725)(-3275 675);
WIRE 16 -1 (-3175 675)(-3275 675);
WIRE 16 -1 (-3275 675)(-3275 625);
WIRE 16 -1 (-3175 625)(-3275 625);
WIRE 16 -1 (-3275 625)(-3275 575);
WIRE 16 -1 (-3175 575)(-3275 575);
WIRE 16 -1 (-3275 575)(-3275 525);
WIRE 16 -1 (-3175 525)(-3275 525);
WIRE 16 -1 (-3275 525)(-3275 475);
WIRE 16 -1 (-1950 6425)(-1950 6375);
WIRE 16 -1 (-1950 6425)(-2075 6425);
WIRE 16 -1 (-1950 6375)(-1950 6325);
WIRE 16 -1 (-1950 6375)(-2075 6375);
WIRE 16 -1 (-1950 6325)(-1950 6275);
WIRE 16 -1 (-2075 6325)(-1950 6325);
WIRE 16 -1 (-1950 6275)(-1950 6225);
WIRE 16 -1 (-2075 6275)(-1950 6275);
WIRE 16 -1 (-1950 6225)(-1950 6175);
WIRE 16 -1 (-2075 6225)(-1950 6225);
WIRE 16 -1 (-1950 6175)(-1950 6125);
WIRE 16 -1 (-2075 6175)(-1950 6175);
WIRE 16 -1 (-1950 6125)(-1950 6075);
WIRE 16 -1 (-2075 6125)(-1950 6125);
WIRE 16 -1 (-1950 6075)(-1950 6025);
WIRE 16 -1 (-2075 6075)(-1950 6075);
WIRE 16 -1 (-1950 6025)(-1950 5975);
WIRE 16 -1 (-2075 6025)(-1950 6025);
WIRE 16 -1 (-1950 5975)(-1950 5925);
WIRE 16 -1 (-2075 5975)(-1950 5975);
WIRE 16 -1 (-1950 5925)(-1950 5875);
WIRE 16 -1 (-1950 5925)(-2075 5925);
WIRE 16 -1 (-1950 5875)(-1950 5825);
WIRE 16 -1 (-1950 5875)(-2075 5875);
WIRE 16 -1 (-1950 5825)(-1950 5775);
WIRE 16 -1 (-1950 5825)(-2075 5825);
WIRE 16 -1 (-1950 5775)(-1950 5725);
WIRE 16 -1 (-1950 5775)(-2075 5775);
WIRE 16 -1 (-1950 5725)(-1950 5675);
WIRE 16 -1 (-1950 5725)(-2075 5725);
WIRE 16 -1 (-1950 5675)(-1950 5625);
WIRE 16 -1 (-1950 5675)(-2075 5675);
WIRE 16 -1 (-1950 5625)(-1950 5575);
WIRE 16 -1 (-2075 5625)(-1950 5625);
WIRE 16 -1 (-1950 5575)(-1950 5525);
WIRE 16 -1 (-2075 5575)(-1950 5575);
WIRE 16 -1 (-1950 5525)(-1950 5475);
WIRE 16 -1 (-1950 5525)(-2075 5525);
WIRE 16 -1 (-1950 5475)(-1950 5425);
WIRE 16 -1 (-1950 5475)(-2075 5475);
WIRE 16 -1 (-1950 5425)(-1950 5375);
WIRE 16 -1 (-1950 5425)(-2075 5425);
WIRE 16 -1 (-1950 5375)(-1950 5325);
WIRE 16 -1 (-1950 5375)(-2075 5375);
WIRE 16 -1 (-1950 5325)(-1950 5275);
WIRE 16 -1 (-1950 5325)(-2075 5325);
WIRE 16 -1 (-1950 5275)(-1950 5225);
WIRE 16 -1 (-1950 5275)(-2075 5275);
WIRE 16 -1 (-1950 5225)(-1950 5175);
WIRE 16 -1 (-2075 5225)(-1950 5225);
WIRE 16 -1 (-1950 5175)(-1950 5125);
WIRE 16 -1 (-2075 5175)(-1950 5175);
WIRE 16 -1 (-1950 5125)(-1950 5075);
WIRE 16 -1 (-1950 5125)(-2075 5125);
WIRE 16 -1 (-1950 5075)(-1950 5025);
WIRE 16 -1 (-1950 5075)(-2075 5075);
WIRE 16 -1 (-1950 5025)(-1950 4975);
WIRE 16 -1 (-1950 5025)(-2075 5025);
WIRE 16 -1 (-1950 4975)(-1950 4925);
WIRE 16 -1 (-1950 4975)(-2075 4975);
WIRE 16 -1 (-1950 4925)(-1950 4875);
WIRE 16 -1 (-1950 4925)(-2075 4925);
WIRE 16 -1 (-1950 4875)(-1950 4825);
WIRE 16 -1 (-1950 4875)(-2075 4875);
WIRE 16 -1 (-1950 4825)(-1950 4775);
WIRE 16 -1 (-2075 4825)(-1950 4825);
WIRE 16 -1 (-1950 4775)(-1950 4725);
WIRE 16 -1 (-2075 4775)(-1950 4775);
WIRE 16 -1 (-1950 4725)(-1950 4675);
WIRE 16 -1 (-1950 4725)(-2075 4725);
WIRE 16 -1 (-1950 4675)(-1950 4625);
WIRE 16 -1 (-1950 4675)(-2075 4675);
WIRE 16 -1 (-1950 4625)(-1950 4575);
WIRE 16 -1 (-1950 4625)(-2075 4625);
WIRE 16 -1 (-1950 4575)(-1950 4525);
WIRE 16 -1 (-1950 4575)(-2075 4575);
WIRE 16 -1 (-1950 4525)(-1950 4475);
WIRE 16 -1 (-1950 4525)(-2075 4525);
WIRE 16 -1 (-1950 4475)(-1950 4425);
WIRE 16 -1 (-1950 4475)(-2075 4475);
WIRE 16 -1 (-1950 4425)(-1950 4375);
WIRE 16 -1 (-2075 4425)(-1950 4425);
WIRE 16 -1 (-1950 4375)(-1950 4325);
WIRE 16 -1 (-2075 4375)(-1950 4375);
WIRE 16 -1 (-1950 4325)(-1950 4275);
WIRE 16 -1 (-1950 4325)(-2075 4325);
WIRE 16 -1 (-1950 4275)(-1950 4225);
WIRE 16 -1 (-1950 4275)(-2075 4275);
WIRE 16 -1 (-1950 4225)(-1950 4175);
WIRE 16 -1 (-1950 4225)(-2075 4225);
WIRE 16 -1 (-1950 4175)(-1950 4125);
WIRE 16 -1 (-1950 4175)(-2075 4175);
WIRE 16 -1 (-1950 4125)(-2075 4125);
WIRE 16 -1 (-1950 4125)(-1950 4075);
WIRE 16 -1 (-1950 4075)(-1950 4025);
WIRE 16 -1 (-1950 4075)(-2075 4075);
WIRE 16 -1 (-1950 4025)(-1950 3975);
WIRE 16 -1 (-2075 4025)(-1950 4025);
WIRE 16 -1 (-1950 3975)(-1950 3925);
WIRE 16 -1 (-2075 3975)(-1950 3975);
WIRE 16 -1 (-1950 3925)(-1950 3875);
WIRE 16 -1 (-1950 3925)(-2075 3925);
WIRE 16 -1 (-1950 3875)(-1950 3825);
WIRE 16 -1 (-1950 3875)(-2075 3875);
WIRE 16 -1 (-1950 3825)(-1950 3775);
WIRE 16 -1 (-1950 3825)(-2075 3825);
WIRE 16 -1 (-1950 3775)(-1950 3725);
WIRE 16 -1 (-1950 3775)(-2075 3775);
WIRE 16 -1 (-1950 3725)(-1950 3675);
WIRE 16 -1 (-1950 3725)(-2075 3725);
WIRE 16 -1 (-1950 3675)(-1950 3625);
WIRE 16 -1 (-1950 3675)(-2075 3675);
WIRE 16 -1 (-1950 3625)(-1950 3575);
WIRE 16 -1 (-2075 3625)(-1950 3625);
WIRE 16 -1 (-1950 3575)(-1950 3525);
WIRE 16 -1 (-2075 3575)(-1950 3575);
WIRE 16 -1 (-1950 3525)(-1950 3475);
WIRE 16 -1 (-1950 3525)(-2075 3525);
WIRE 16 -1 (-1950 3475)(-1950 3425);
WIRE 16 -1 (-1950 3475)(-2075 3475);
WIRE 16 -1 (-1950 3425)(-1950 3375);
WIRE 16 -1 (-1950 3425)(-2075 3425);
WIRE 16 -1 (-1950 3375)(-1950 3325);
WIRE 16 -1 (-1950 3375)(-2075 3375);
WIRE 16 -1 (-1950 3325)(-1950 3275);
WIRE 16 -1 (-1950 3325)(-2075 3325);
WIRE 16 -1 (-1950 3275)(-1950 3225);
WIRE 16 -1 (-1950 3275)(-2075 3275);
WIRE 16 -1 (-1950 3225)(-1950 3175);
WIRE 16 -1 (-2075 3225)(-1950 3225);
WIRE 16 -1 (-1950 3175)(-1950 3125);
WIRE 16 -1 (-2075 3175)(-1950 3175);
WIRE 16 -1 (-1950 3125)(-1950 3075);
WIRE 16 -1 (-1950 3125)(-2075 3125);
WIRE 16 -1 (-1950 3075)(-1950 3025);
WIRE 16 -1 (-1950 3075)(-2075 3075);
WIRE 16 -1 (-1950 3025)(-1950 2975);
WIRE 16 -1 (-1950 3025)(-2075 3025);
WIRE 16 -1 (-1950 2975)(-1950 2925);
WIRE 16 -1 (-1950 2975)(-2075 2975);
WIRE 16 -1 (-1950 2925)(-1950 2875);
WIRE 16 -1 (-1950 2925)(-2075 2925);
WIRE 16 -1 (-1950 2875)(-1950 2825);
WIRE 16 -1 (-1950 2875)(-2075 2875);
WIRE 16 -1 (-1950 2825)(-1950 2775);
WIRE 16 -1 (-2075 2825)(-1950 2825);
WIRE 16 -1 (-1950 2775)(-1950 2725);
WIRE 16 -1 (-2075 2775)(-1950 2775);
WIRE 16 -1 (-1950 2725)(-1950 2675);
WIRE 16 -1 (-1950 2725)(-2075 2725);
WIRE 16 -1 (-1950 2675)(-1950 2625);
WIRE 16 -1 (-1950 2675)(-2075 2675);
WIRE 16 -1 (-1950 2625)(-1950 2575);
WIRE 16 -1 (-1950 2625)(-2075 2625);
WIRE 16 -1 (-1950 2575)(-1950 2525);
WIRE 16 -1 (-1950 2575)(-2075 2575);
WIRE 16 -1 (-1950 2525)(-1950 2475);
WIRE 16 -1 (-1950 2525)(-2075 2525);
WIRE 16 -1 (-1950 2475)(-1950 2425);
WIRE 16 -1 (-1950 2475)(-2075 2475);
WIRE 16 -1 (-1950 2425)(-1950 2375);
WIRE 16 -1 (-2075 2425)(-1950 2425);
WIRE 16 -1 (-1950 2375)(-1950 2325);
WIRE 16 -1 (-2075 2375)(-1950 2375);
WIRE 16 -1 (-1950 2325)(-1950 2275);
WIRE 16 -1 (-1950 2325)(-2075 2325);
WIRE 16 -1 (-1950 2275)(-1950 2225);
WIRE 16 -1 (-1950 2275)(-2075 2275);
WIRE 16 -1 (-1950 2225)(-1950 2175);
WIRE 16 -1 (-1950 2225)(-2075 2225);
WIRE 16 -1 (-1950 2175)(-1950 2125);
WIRE 16 -1 (-1950 2175)(-2075 2175);
WIRE 16 -1 (-1950 2125)(-1950 2075);
WIRE 16 -1 (-1950 2125)(-2075 2125);
WIRE 16 -1 (-1950 2075)(-1950 2025);
WIRE 16 -1 (-1950 2075)(-2075 2075);
WIRE 16 -1 (-1950 2025)(-1950 1975);
WIRE 16 -1 (-2075 2025)(-1950 2025);
WIRE 16 -1 (-1950 1975)(-1950 1925);
WIRE 16 -1 (-2075 1975)(-1950 1975);
WIRE 16 -1 (-1950 1925)(-1950 1875);
WIRE 16 -1 (-1950 1925)(-2075 1925);
WIRE 16 -1 (-1950 1875)(-1950 1825);
WIRE 16 -1 (-1950 1875)(-2075 1875);
WIRE 16 -1 (-1950 1825)(-1950 1775);
WIRE 16 -1 (-1950 1825)(-2075 1825);
WIRE 16 -1 (-1950 1775)(-1950 1725);
WIRE 16 -1 (-1950 1775)(-2075 1775);
WIRE 16 -1 (-1950 1725)(-1950 1675);
WIRE 16 -1 (-1950 1725)(-2075 1725);
WIRE 16 -1 (-1950 1675)(-1950 1625);
WIRE 16 -1 (-1950 1675)(-2075 1675);
WIRE 16 -1 (-1950 1625)(-1950 1575);
WIRE 16 -1 (-2075 1625)(-1950 1625);
WIRE 16 -1 (-1950 1575)(-1950 1525);
WIRE 16 -1 (-2075 1575)(-1950 1575);
WIRE 16 -1 (-1950 1525)(-1950 1475);
WIRE 16 -1 (-1950 1525)(-2075 1525);
WIRE 16 -1 (-1950 1475)(-1950 1425);
WIRE 16 -1 (-1950 1475)(-2075 1475);
WIRE 16 -1 (-1950 1425)(-1950 1375);
WIRE 16 -1 (-1950 1425)(-2075 1425);
WIRE 16 -1 (-1950 1375)(-1950 1325);
WIRE 16 -1 (-1950 1375)(-2075 1375);
WIRE 16 -1 (-1950 1325)(-1950 1275);
WIRE 16 -1 (-1950 1325)(-2075 1325);
WIRE 16 -1 (-1950 1275)(-1950 1225);
WIRE 16 -1 (-1950 1275)(-2075 1275);
WIRE 16 -1 (-1950 1225)(-1950 1175);
WIRE 16 -1 (-2075 1225)(-1950 1225);
WIRE 16 -1 (-1950 1175)(-1950 1125);
WIRE 16 -1 (-2075 1175)(-1950 1175);
WIRE 16 -1 (-1950 1125)(-1950 1075);
WIRE 16 -1 (-1950 1125)(-2075 1125);
WIRE 16 -1 (-1950 1075)(-1950 1025);
WIRE 16 -1 (-1950 1075)(-2075 1075);
WIRE 16 -1 (-1950 1025)(-1950 975);
WIRE 16 -1 (-1950 1025)(-2075 1025);
WIRE 16 -1 (-1950 975)(-1950 925);
WIRE 16 -1 (-1950 975)(-2075 975);
WIRE 16 -1 (-1950 925)(-1950 875);
WIRE 16 -1 (-1950 925)(-2075 925);
WIRE 16 -1 (-1950 875)(-1950 825);
WIRE 16 -1 (-1950 875)(-2075 875);
WIRE 16 -1 (-1950 825)(-1950 775);
WIRE 16 -1 (-2075 825)(-1950 825);
WIRE 16 -1 (-1950 775)(-1950 725);
WIRE 16 -1 (-2075 775)(-1950 775);
WIRE 16 -1 (-1950 725)(-1950 675);
WIRE 16 -1 (-1950 725)(-2075 725);
WIRE 16 -1 (-1950 675)(-1950 625);
WIRE 16 -1 (-1950 675)(-2075 675);
WIRE 16 -1 (-1950 625)(-1950 575);
WIRE 16 -1 (-1950 625)(-2075 625);
WIRE 16 -1 (-1950 575)(-1950 525);
WIRE 16 -1 (-1950 575)(-2075 575);
WIRE 16 -1 (-1950 525)(-1950 500);
WIRE 16 -1 (-1950 525)(-2075 525);
WIRE 16 -1 (-1650 6425)(-1550 6425);
WIRE 16 -1 (-1650 6425)(-1650 6375);
WIRE 16 -1 (-1650 6375)(-1550 6375);
WIRE 16 -1 (-1650 6375)(-1650 6325);
WIRE 16 -1 (-1650 6325)(-1550 6325);
WIRE 16 -1 (-1650 6325)(-1650 6275);
WIRE 16 -1 (-1650 6275)(-1550 6275);
WIRE 16 -1 (-1650 6275)(-1650 6225);
WIRE 16 -1 (-1650 6225)(-1550 6225);
WIRE 16 -1 (-1650 6225)(-1650 6175);
WIRE 16 -1 (-1550 6175)(-1650 6175);
WIRE 16 -1 (-1650 6175)(-1650 6125);
WIRE 16 -1 (-1550 6125)(-1650 6125);
WIRE 16 -1 (-1650 6125)(-1650 6075);
WIRE 16 -1 (-1650 6075)(-1550 6075);
WIRE 16 -1 (-1650 6075)(-1650 6025);
WIRE 16 -1 (-1650 6025)(-1550 6025);
WIRE 16 -1 (-1650 6025)(-1650 5975);
WIRE 16 -1 (-1650 5975)(-1550 5975);
WIRE 16 -1 (-1650 5975)(-1650 5925);
WIRE 16 -1 (-1650 5925)(-1550 5925);
WIRE 16 -1 (-1650 5925)(-1650 5875);
WIRE 16 -1 (-1650 5875)(-1550 5875);
WIRE 16 -1 (-1650 5875)(-1650 5825);
WIRE 16 -1 (-1650 5825)(-1550 5825);
WIRE 16 -1 (-1650 5825)(-1650 5775);
WIRE 16 -1 (-1550 5775)(-1650 5775);
WIRE 16 -1 (-1650 5775)(-1650 5725);
WIRE 16 -1 (-1550 5725)(-1650 5725);
WIRE 16 -1 (-1650 5725)(-1650 5675);
WIRE 16 -1 (-1650 5675)(-1550 5675);
WIRE 16 -1 (-1650 5675)(-1650 5625);
WIRE 16 -1 (-1650 5625)(-1550 5625);
WIRE 16 -1 (-1650 5625)(-1650 5575);
WIRE 16 -1 (-1650 5575)(-1550 5575);
WIRE 16 -1 (-1650 5575)(-1650 5525);
WIRE 16 -1 (-1650 5525)(-1550 5525);
WIRE 16 -1 (-1650 5525)(-1650 5475);
WIRE 16 -1 (-1650 5475)(-1550 5475);
WIRE 16 -1 (-1650 5475)(-1650 5425);
WIRE 16 -1 (-1650 5425)(-1550 5425);
WIRE 16 -1 (-1650 5425)(-1650 5375);
WIRE 16 -1 (-1550 5375)(-1650 5375);
WIRE 16 -1 (-1650 5375)(-1650 5325);
WIRE 16 -1 (-1550 5325)(-1650 5325);
WIRE 16 -1 (-1650 5325)(-1650 5275);
WIRE 16 -1 (-1650 5275)(-1550 5275);
WIRE 16 -1 (-1650 5275)(-1650 5225);
WIRE 16 -1 (-1650 5225)(-1550 5225);
WIRE 16 -1 (-1650 5225)(-1650 5175);
WIRE 16 -1 (-1650 5175)(-1550 5175);
WIRE 16 -1 (-1650 5175)(-1650 5125);
WIRE 16 -1 (-1650 5125)(-1550 5125);
WIRE 16 -1 (-1650 5125)(-1650 5075);
WIRE 16 -1 (-1650 5075)(-1550 5075);
WIRE 16 -1 (-1650 5075)(-1650 5025);
WIRE 16 -1 (-1650 5025)(-1550 5025);
WIRE 16 -1 (-1650 5025)(-1650 4975);
WIRE 16 -1 (-1550 4975)(-1650 4975);
WIRE 16 -1 (-1650 4975)(-1650 4925);
WIRE 16 -1 (-1550 4925)(-1650 4925);
WIRE 16 -1 (-1650 4925)(-1650 4875);
WIRE 16 -1 (-1650 4875)(-1550 4875);
WIRE 16 -1 (-1650 4875)(-1650 4825);
WIRE 16 -1 (-1650 4825)(-1550 4825);
WIRE 16 -1 (-1650 4825)(-1650 4775);
WIRE 16 -1 (-1650 4775)(-1550 4775);
WIRE 16 -1 (-1650 4775)(-1650 4725);
WIRE 16 -1 (-1650 4725)(-1550 4725);
WIRE 16 -1 (-1650 4725)(-1650 4675);
WIRE 16 -1 (-1650 4675)(-1550 4675);
WIRE 16 -1 (-1650 4675)(-1650 4625);
WIRE 16 -1 (-1650 4625)(-1550 4625);
WIRE 16 -1 (-1650 4625)(-1650 4575);
WIRE 16 -1 (-1550 4575)(-1650 4575);
WIRE 16 -1 (-1650 4575)(-1650 4525);
WIRE 16 -1 (-1550 4525)(-1650 4525);
WIRE 16 -1 (-1650 4525)(-1650 4475);
WIRE 16 -1 (-1650 4475)(-1550 4475);
WIRE 16 -1 (-1650 4475)(-1650 4425);
WIRE 16 -1 (-1650 4425)(-1550 4425);
WIRE 16 -1 (-1650 4425)(-1650 4375);
WIRE 16 -1 (-1650 4375)(-1550 4375);
WIRE 16 -1 (-1650 4375)(-1650 4325);
WIRE 16 -1 (-1650 4325)(-1550 4325);
WIRE 16 -1 (-1650 4325)(-1650 4275);
WIRE 16 -1 (-1650 4275)(-1550 4275);
WIRE 16 -1 (-1650 4275)(-1650 4225);
WIRE 16 -1 (-1650 4225)(-1550 4225);
WIRE 16 -1 (-1650 4225)(-1650 4175);
WIRE 16 -1 (-1550 4175)(-1650 4175);
WIRE 16 -1 (-1650 4175)(-1650 4125);
WIRE 16 -1 (-1550 4125)(-1650 4125);
WIRE 16 -1 (-1650 4125)(-1650 4075);
WIRE 16 -1 (-1650 4075)(-1550 4075);
WIRE 16 -1 (-1650 4075)(-1650 4025);
WIRE 16 -1 (-1650 4025)(-1550 4025);
WIRE 16 -1 (-1650 4025)(-1650 3975);
WIRE 16 -1 (-1650 3975)(-1550 3975);
WIRE 16 -1 (-1650 3975)(-1650 3925);
WIRE 16 -1 (-1650 3925)(-1550 3925);
WIRE 16 -1 (-1650 3925)(-1650 3875);
WIRE 16 -1 (-1650 3875)(-1550 3875);
WIRE 16 -1 (-1650 3875)(-1650 3825);
WIRE 16 -1 (-1650 3825)(-1550 3825);
WIRE 16 -1 (-1650 3825)(-1650 3775);
WIRE 16 -1 (-1550 3775)(-1650 3775);
WIRE 16 -1 (-1650 3775)(-1650 3725);
WIRE 16 -1 (-1550 3725)(-1650 3725);
WIRE 16 -1 (-1650 3725)(-1650 3675);
WIRE 16 -1 (-1650 3675)(-1550 3675);
WIRE 16 -1 (-1650 3675)(-1650 3625);
WIRE 16 -1 (-1650 3625)(-1550 3625);
WIRE 16 -1 (-1650 3625)(-1650 3575);
WIRE 16 -1 (-1650 3575)(-1550 3575);
WIRE 16 -1 (-1650 3575)(-1650 3525);
WIRE 16 -1 (-1650 3525)(-1550 3525);
WIRE 16 -1 (-1650 3525)(-1650 3475);
WIRE 16 -1 (-1650 3475)(-1550 3475);
WIRE 16 -1 (-1650 3475)(-1650 3425);
WIRE 16 -1 (-1650 3425)(-1550 3425);
WIRE 16 -1 (-1650 3425)(-1650 3375);
WIRE 16 -1 (-1550 3375)(-1650 3375);
WIRE 16 -1 (-1650 3375)(-1650 3325);
WIRE 16 -1 (-1550 3325)(-1650 3325);
WIRE 16 -1 (-1650 3325)(-1650 3275);
WIRE 16 -1 (-1650 3275)(-1550 3275);
WIRE 16 -1 (-1650 3275)(-1650 3225);
WIRE 16 -1 (-1650 3225)(-1550 3225);
WIRE 16 -1 (-1650 3225)(-1650 3175);
WIRE 16 -1 (-1650 3175)(-1550 3175);
WIRE 16 -1 (-1650 3175)(-1650 3125);
WIRE 16 -1 (-1650 3125)(-1550 3125);
WIRE 16 -1 (-1650 3125)(-1650 3075);
WIRE 16 -1 (-1650 3075)(-1550 3075);
WIRE 16 -1 (-1650 3075)(-1650 3025);
WIRE 16 -1 (-1650 3025)(-1550 3025);
WIRE 16 -1 (-1650 3025)(-1650 2975);
WIRE 16 -1 (-1550 2975)(-1650 2975);
WIRE 16 -1 (-1650 2975)(-1650 2925);
WIRE 16 -1 (-1550 2925)(-1650 2925);
WIRE 16 -1 (-1650 2925)(-1650 2875);
WIRE 16 -1 (-1650 2875)(-1550 2875);
WIRE 16 -1 (-1650 2875)(-1650 2825);
WIRE 16 -1 (-1650 2825)(-1550 2825);
WIRE 16 -1 (-1650 2825)(-1650 2775);
WIRE 16 -1 (-1650 2775)(-1550 2775);
WIRE 16 -1 (-1650 2775)(-1650 2725);
WIRE 16 -1 (-1650 2725)(-1550 2725);
WIRE 16 -1 (-1650 2725)(-1650 2675);
WIRE 16 -1 (-1650 2675)(-1550 2675);
WIRE 16 -1 (-1650 2675)(-1650 2625);
WIRE 16 -1 (-1650 2625)(-1550 2625);
WIRE 16 -1 (-1650 2625)(-1650 2575);
WIRE 16 -1 (-1550 2575)(-1650 2575);
WIRE 16 -1 (-1650 2575)(-1650 2525);
WIRE 16 -1 (-1550 2525)(-1650 2525);
WIRE 16 -1 (-1650 2525)(-1650 2475);
WIRE 16 -1 (-1650 2475)(-1550 2475);
WIRE 16 -1 (-1650 2475)(-1650 2425);
WIRE 16 -1 (-1650 2425)(-1550 2425);
WIRE 16 -1 (-1650 2425)(-1650 2375);
WIRE 16 -1 (-1650 2375)(-1550 2375);
WIRE 16 -1 (-1650 2375)(-1650 2325);
WIRE 16 -1 (-1650 2325)(-1550 2325);
WIRE 16 -1 (-1650 2325)(-1650 2275);
WIRE 16 -1 (-1650 2275)(-1550 2275);
WIRE 16 -1 (-1650 2275)(-1650 2225);
WIRE 16 -1 (-1650 2225)(-1550 2225);
WIRE 16 -1 (-1650 2225)(-1650 2175);
WIRE 16 -1 (-1550 2175)(-1650 2175);
WIRE 16 -1 (-1650 2175)(-1650 2125);
WIRE 16 -1 (-1550 2125)(-1650 2125);
WIRE 16 -1 (-1650 2125)(-1650 2075);
WIRE 16 -1 (-1650 2075)(-1550 2075);
WIRE 16 -1 (-1650 2075)(-1650 2025);
WIRE 16 -1 (-1650 2025)(-1550 2025);
WIRE 16 -1 (-1650 2025)(-1650 1975);
WIRE 16 -1 (-1650 1975)(-1550 1975);
WIRE 16 -1 (-1650 1975)(-1650 1925);
WIRE 16 -1 (-1650 1925)(-1550 1925);
WIRE 16 -1 (-1650 1925)(-1650 1875);
WIRE 16 -1 (-1650 1875)(-1550 1875);
WIRE 16 -1 (-1650 1875)(-1650 1825);
WIRE 16 -1 (-1650 1825)(-1550 1825);
WIRE 16 -1 (-1650 1825)(-1650 1775);
WIRE 16 -1 (-1550 1775)(-1650 1775);
WIRE 16 -1 (-1650 1775)(-1650 1725);
WIRE 16 -1 (-1550 1725)(-1650 1725);
WIRE 16 -1 (-1650 1725)(-1650 1675);
WIRE 16 -1 (-1650 1675)(-1550 1675);
WIRE 16 -1 (-1650 1675)(-1650 1625);
WIRE 16 -1 (-1650 1625)(-1550 1625);
WIRE 16 -1 (-1650 1625)(-1650 1575);
WIRE 16 -1 (-1650 1575)(-1550 1575);
WIRE 16 -1 (-1650 1575)(-1650 1525);
WIRE 16 -1 (-1650 1525)(-1550 1525);
WIRE 16 -1 (-1650 1525)(-1650 1475);
WIRE 16 -1 (-1650 1475)(-1550 1475);
WIRE 16 -1 (-1650 1475)(-1650 1425);
WIRE 16 -1 (-1650 1425)(-1550 1425);
WIRE 16 -1 (-1650 1425)(-1650 1375);
WIRE 16 -1 (-1550 1375)(-1650 1375);
WIRE 16 -1 (-1650 1375)(-1650 1325);
WIRE 16 -1 (-1550 1325)(-1650 1325);
WIRE 16 -1 (-1650 1325)(-1650 1275);
WIRE 16 -1 (-1650 1275)(-1550 1275);
WIRE 16 -1 (-1650 1275)(-1650 1225);
WIRE 16 -1 (-1650 1225)(-1550 1225);
WIRE 16 -1 (-1650 1225)(-1650 1175);
WIRE 16 -1 (-1650 1175)(-1550 1175);
WIRE 16 -1 (-1650 1175)(-1650 1125);
WIRE 16 -1 (-1650 1125)(-1550 1125);
WIRE 16 -1 (-1650 1125)(-1650 1075);
WIRE 16 -1 (-1650 1075)(-1550 1075);
WIRE 16 -1 (-1650 1075)(-1650 1025);
WIRE 16 -1 (-1650 1025)(-1550 1025);
WIRE 16 -1 (-1650 1025)(-1650 975);
WIRE 16 -1 (-1550 975)(-1650 975);
WIRE 16 -1 (-1650 975)(-1650 925);
WIRE 16 -1 (-1550 925)(-1650 925);
WIRE 16 -1 (-1650 925)(-1650 875);
WIRE 16 -1 (-1550 875)(-1650 875);
WIRE 16 -1 (-1650 875)(-1650 825);
WIRE 16 -1 (-1550 825)(-1650 825);
WIRE 16 -1 (-1650 825)(-1650 775);
WIRE 16 -1 (-1550 775)(-1650 775);
WIRE 16 -1 (-1650 775)(-1650 725);
WIRE 16 -1 (-1550 725)(-1650 725);
WIRE 16 -1 (-1650 725)(-1650 675);
WIRE 16 -1 (-1550 675)(-1650 675);
WIRE 16 -1 (-1650 675)(-1650 625);
WIRE 16 -1 (-1550 625)(-1650 625);
WIRE 16 -1 (-1650 625)(-1650 575);
WIRE 16 -1 (-1550 575)(-1650 575);
WIRE 16 -1 (-1650 575)(-1650 525);
WIRE 16 -1 (-1550 525)(-1650 525);
WIRE 16 -1 (-1650 525)(-1650 500);
WIRE 16 -1 (-325 6425)(-450 6425);
WIRE 16 -1 (-325 6425)(-325 6375);
WIRE 16 -1 (-325 6375)(-325 6325);
WIRE 16 -1 (-325 6375)(-450 6375);
WIRE 16 -1 (-325 6325)(-325 6275);
WIRE 16 -1 (-450 6325)(-325 6325);
WIRE 16 -1 (-325 6275)(-325 6225);
WIRE 16 -1 (-450 6275)(-325 6275);
WIRE 16 -1 (-325 6225)(-325 6175);
WIRE 16 -1 (-450 6225)(-325 6225);
WIRE 16 -1 (-450 6175)(-325 6175);
WIRE 16 -1 (-325 6175)(-325 6125);
WIRE 16 -1 (-325 6125)(-325 6075);
WIRE 16 -1 (-450 6125)(-325 6125);
WIRE 16 -1 (-325 6075)(-325 6025);
WIRE 16 -1 (-450 6075)(-325 6075);
WIRE 16 -1 (-325 6025)(-325 5975);
WIRE 16 -1 (-450 6025)(-325 6025);
WIRE 16 -1 (-325 5975)(-325 5925);
WIRE 16 -1 (-450 5975)(-325 5975);
WIRE 16 -1 (-325 5925)(-450 5925);
WIRE 16 -1 (-325 5925)(-325 5875);
WIRE 16 -1 (-325 5875)(-325 5825);
WIRE 16 -1 (-325 5875)(-450 5875);
WIRE 16 -1 (-325 5825)(-325 5775);
WIRE 16 -1 (-325 5825)(-450 5825);
WIRE 16 -1 (-325 5775)(-325 5725);
WIRE 16 -1 (-325 5775)(-450 5775);
WIRE 16 -1 (-325 5725)(-325 5675);
WIRE 16 -1 (-325 5725)(-450 5725);
WIRE 16 -1 (-325 5675)(-450 5675);
WIRE 16 -1 (-325 5675)(-325 5625);
WIRE 16 -1 (-325 5625)(-325 5575);
WIRE 16 -1 (-450 5625)(-325 5625);
WIRE 16 -1 (-325 5575)(-325 5525);
WIRE 16 -1 (-450 5575)(-325 5575);
WIRE 16 -1 (-325 5525)(-325 5475);
WIRE 16 -1 (-325 5525)(-450 5525);
WIRE 16 -1 (-325 5475)(-325 5425);
WIRE 16 -1 (-325 5475)(-450 5475);
WIRE 16 -1 (-325 5425)(-450 5425);
WIRE 16 -1 (-325 5425)(-325 5375);
WIRE 16 -1 (-325 5375)(-325 5325);
WIRE 16 -1 (-325 5375)(-450 5375);
WIRE 16 -1 (-325 5325)(-325 5275);
WIRE 16 -1 (-325 5325)(-450 5325);
WIRE 16 -1 (-325 5275)(-325 5225);
WIRE 16 -1 (-325 5275)(-450 5275);
WIRE 16 -1 (-325 5225)(-325 5175);
WIRE 16 -1 (-450 5225)(-325 5225);
WIRE 16 -1 (-325 5175)(-325 5125);
WIRE 16 -1 (-450 5175)(-325 5175);
WIRE 16 -1 (-325 5125)(-450 5125);
WIRE 16 -1 (-325 5125)(-325 5075);
WIRE 16 -1 (-325 5075)(-325 5025);
WIRE 16 -1 (-325 5075)(-450 5075);
WIRE 16 -1 (-325 5025)(-325 4975);
WIRE 16 -1 (-325 5025)(-450 5025);
WIRE 16 -1 (-325 4975)(-325 4925);
WIRE 16 -1 (-325 4975)(-450 4975);
WIRE 16 -1 (-325 4925)(-325 4875);
WIRE 16 -1 (-325 4925)(-450 4925);
WIRE 16 -1 (-325 4875)(-450 4875);
WIRE 16 -1 (-325 4875)(-325 4825);
WIRE 16 -1 (-325 4825)(-325 4775);
WIRE 16 -1 (-450 4825)(-325 4825);
WIRE 16 -1 (-325 4775)(-325 4725);
WIRE 16 -1 (-450 4775)(-325 4775);
WIRE 16 -1 (-325 4725)(-325 4675);
WIRE 16 -1 (-325 4725)(-450 4725);
WIRE 16 -1 (-325 4675)(-325 4625);
WIRE 16 -1 (-325 4675)(-450 4675);
WIRE 16 -1 (-325 4625)(-450 4625);
WIRE 16 -1 (-325 4625)(-325 4575);
WIRE 16 -1 (-325 4575)(-325 4525);
WIRE 16 -1 (-325 4575)(-450 4575);
WIRE 16 -1 (-325 4525)(-325 4475);
WIRE 16 -1 (-325 4525)(-450 4525);
WIRE 16 -1 (-325 4475)(-325 4425);
WIRE 16 -1 (-325 4475)(-450 4475);
WIRE 16 -1 (-325 4425)(-325 4375);
WIRE 16 -1 (-450 4425)(-325 4425);
WIRE 16 -1 (-450 4375)(-325 4375);
WIRE 16 -1 (-325 4375)(-325 4325);
WIRE 16 -1 (-325 4325)(-325 4275);
WIRE 16 -1 (-325 4325)(-450 4325);
WIRE 16 -1 (-325 4275)(-325 4225);
WIRE 16 -1 (-325 4275)(-450 4275);
WIRE 16 -1 (-325 4225)(-325 4175);
WIRE 16 -1 (-325 4225)(-450 4225);
WIRE 16 -1 (-325 4175)(-325 4125);
WIRE 16 -1 (-325 4175)(-450 4175);
WIRE 16 -1 (-325 4125)(-450 4125);
WIRE 16 -1 (-325 4125)(-325 4075);
WIRE 16 -1 (-325 4075)(-325 4025);
WIRE 16 -1 (-325 4075)(-450 4075);
WIRE 16 -1 (-325 4025)(-325 3975);
WIRE 16 -1 (-450 4025)(-325 4025);
WIRE 16 -1 (-325 3975)(-325 3925);
WIRE 16 -1 (-450 3975)(-325 3975);
WIRE 16 -1 (-325 3925)(-325 3875);
WIRE 16 -1 (-325 3925)(-450 3925);
WIRE 16 -1 (-325 3875)(-450 3875);
WIRE 16 -1 (-325 3875)(-325 3825);
WIRE 16 -1 (-325 3825)(-325 3775);
WIRE 16 -1 (-325 3825)(-450 3825);
WIRE 16 -1 (-325 3775)(-325 3725);
WIRE 16 -1 (-325 3775)(-450 3775);
WIRE 16 -1 (-325 3725)(-325 3675);
WIRE 16 -1 (-325 3725)(-450 3725);
WIRE 16 -1 (-325 3675)(-325 3625);
WIRE 16 -1 (-325 3675)(-450 3675);
WIRE 16 -1 (-450 3625)(-325 3625);
WIRE 16 -1 (-325 3625)(-325 3575);
WIRE 16 -1 (-325 3575)(-325 3525);
WIRE 16 -1 (-450 3575)(-325 3575);
WIRE 16 -1 (-325 3525)(-325 3475);
WIRE 16 -1 (-325 3525)(-450 3525);
WIRE 16 -1 (-325 3475)(-325 3425);
WIRE 16 -1 (-325 3475)(-450 3475);
WIRE 16 -1 (-325 3425)(-325 3375);
WIRE 16 -1 (-325 3425)(-450 3425);
WIRE 16 -1 (-325 3375)(-450 3375);
WIRE 16 -1 (-325 3375)(-325 3325);
WIRE 16 -1 (-325 3325)(-325 3275);
WIRE 16 -1 (-325 3325)(-450 3325);
WIRE 16 -1 (-325 3275)(-325 3225);
WIRE 16 -1 (-325 3275)(-450 3275);
WIRE 16 -1 (-325 3225)(-325 3175);
WIRE 16 -1 (-450 3225)(-325 3225);
WIRE 16 -1 (-325 3175)(-325 3125);
WIRE 16 -1 (-450 3175)(-325 3175);
WIRE 16 -1 (-325 3125)(-325 3075);
WIRE 16 -1 (-325 3125)(-450 3125);
WIRE 16 -1 (-325 3075)(-450 3075);
WIRE 16 -1 (-325 3075)(-325 3025);
WIRE 16 -1 (-325 3025)(-325 2975);
WIRE 16 -1 (-325 3025)(-450 3025);
WIRE 16 -1 (-325 2975)(-325 2925);
WIRE 16 -1 (-325 2975)(-450 2975);
WIRE 16 -1 (-325 2925)(-325 2875);
WIRE 16 -1 (-325 2925)(-450 2925);
WIRE 16 -1 (-325 2875)(-325 2825);
WIRE 16 -1 (-325 2875)(-450 2875);
WIRE 16 -1 (-450 2825)(-325 2825);
WIRE 16 -1 (-325 2825)(-325 2775);
WIRE 16 -1 (-325 2775)(-325 2725);
WIRE 16 -1 (-450 2775)(-325 2775);
WIRE 16 -1 (-325 2725)(-325 2675);
WIRE 16 -1 (-325 2725)(-450 2725);
WIRE 16 -1 (-325 2675)(-325 2625);
WIRE 16 -1 (-325 2675)(-450 2675);
WIRE 16 -1 (-325 2625)(-325 2575);
WIRE 16 -1 (-325 2625)(-450 2625);
WIRE 16 -1 (-325 2575)(-450 2575);
WIRE 16 -1 (-325 2575)(-325 2525);
WIRE 16 -1 (-325 2525)(-325 2475);
WIRE 16 -1 (-325 2525)(-450 2525);
WIRE 16 -1 (-325 2475)(-325 2425);
WIRE 16 -1 (-325 2475)(-450 2475);
WIRE 16 -1 (-325 2425)(-325 2375);
WIRE 16 -1 (-450 2425)(-325 2425);
WIRE 16 -1 (-325 2375)(-325 2325);
WIRE 16 -1 (-450 2375)(-325 2375);
WIRE 16 -1 (-325 2325)(-450 2325);
WIRE 16 -1 (-325 2325)(-325 2275);
WIRE 16 -1 (-325 2275)(-325 2225);
WIRE 16 -1 (-325 2275)(-450 2275);
WIRE 16 -1 (-325 2225)(-325 2175);
WIRE 16 -1 (-325 2225)(-450 2225);
WIRE 16 -1 (-325 2175)(-325 2125);
WIRE 16 -1 (-325 2175)(-450 2175);
WIRE 16 -1 (-325 2125)(-325 2075);
WIRE 16 -1 (-325 2125)(-450 2125);
WIRE 16 -1 (-325 2075)(-450 2075);
WIRE 16 -1 (-325 2075)(-325 2025);
WIRE 16 -1 (-325 2025)(-325 1975);
WIRE 16 -1 (-450 2025)(-325 2025);
WIRE 16 -1 (-325 1975)(-325 1925);
WIRE 16 -1 (-450 1975)(-325 1975);
WIRE 16 -1 (-325 1925)(-325 1875);
WIRE 16 -1 (-325 1925)(-450 1925);
WIRE 16 -1 (-325 1875)(-325 1825);
WIRE 16 -1 (-325 1875)(-450 1875);
WIRE 16 -1 (-325 1825)(-450 1825);
WIRE 16 -1 (-325 1825)(-325 1775);
WIRE 16 -1 (-325 1775)(-325 1725);
WIRE 16 -1 (-325 1775)(-450 1775);
WIRE 16 -1 (-325 1725)(-325 1675);
WIRE 16 -1 (-325 1725)(-450 1725);
WIRE 16 -1 (-325 1675)(-325 1625);
WIRE 16 -1 (-325 1675)(-450 1675);
WIRE 16 -1 (-325 1625)(-325 1575);
WIRE 16 -1 (-450 1625)(-325 1625);
WIRE 16 -1 (-450 1575)(-325 1575);
WIRE 16 -1 (-325 1575)(-325 1525);
WIRE 16 -1 (-325 1525)(-325 1475);
WIRE 16 -1 (-325 1525)(-450 1525);
WIRE 16 -1 (-325 1475)(-325 1425);
WIRE 16 -1 (-325 1475)(-450 1475);
WIRE 16 -1 (-325 1425)(-325 1375);
WIRE 16 -1 (-325 1425)(-450 1425);
WIRE 16 -1 (-325 1375)(-325 1325);
WIRE 16 -1 (-325 1375)(-450 1375);
WIRE 16 -1 (-325 1325)(-450 1325);
WIRE 16 -1 (-325 1325)(-325 1275);
WIRE 16 -1 (-325 1275)(-325 1225);
WIRE 16 -1 (-325 1275)(-450 1275);
WIRE 16 -1 (-325 1225)(-325 1175);
WIRE 16 -1 (-450 1225)(-325 1225);
WIRE 16 -1 (-325 1175)(-325 1125);
WIRE 16 -1 (-450 1175)(-325 1175);
WIRE 16 -1 (-325 1125)(-325 1075);
WIRE 16 -1 (-325 1125)(-450 1125);
WIRE 16 -1 (-325 1075)(-325 1025);
WIRE 16 -1 (-325 1075)(-450 1075);
WIRE 16 -1 (-325 1025)(-450 1025);
WIRE 16 -1 (-325 1025)(-325 975);
WIRE 16 -1 (-325 975)(-325 925);
WIRE 16 -1 (-325 975)(-450 975);
WIRE 16 -1 (-325 925)(-325 875);
WIRE 16 -1 (-325 925)(-450 925);
WIRE 16 -1 (-325 875)(-325 825);
WIRE 16 -1 (-325 875)(-450 875);
WIRE 16 -1 (-325 825)(-325 775);
WIRE 16 -1 (-450 825)(-325 825);
WIRE 16 -1 (-450 775)(-325 775);
WIRE 16 -1 (-325 775)(-325 725);
WIRE 16 -1 (-325 725)(-325 675);
WIRE 16 -1 (-325 725)(-450 725);
WIRE 16 -1 (-325 675)(-325 625);
WIRE 16 -1 (-325 675)(-450 675);
WIRE 16 -1 (-325 625)(-325 575);
WIRE 16 -1 (-325 625)(-450 625);
WIRE 16 -1 (-325 575)(-325 525);
WIRE 16 -1 (-325 575)(-450 575);
WIRE 16 -1 (-325 525)(-450 525);
WIRE 16 -1 (-325 525)(-325 500);
DOT 1 (-9275 3100);
DOT 1 (-9275 3150);
DOT 1 (-9275 450);
DOT 1 (-9275 500);
DOT 1 (-9275 600);
DOT 1 (-9275 550);
DOT 1 (-9275 750);
DOT 1 (-9275 700);
DOT 1 (-9275 800);
DOT 1 (-9275 850);
DOT 1 (-9275 900);
DOT 1 (-9275 1000);
DOT 1 (-9275 950);
DOT 1 (-9275 1150);
DOT 1 (-9275 1100);
DOT 1 (-9275 1050);
DOT 1 (-9275 1200);
DOT 1 (-9275 1250);
DOT 1 (-9275 1400);
DOT 1 (-9275 1350);
DOT 1 (-9275 1300);
DOT 1 (-9275 1500);
DOT 1 (-9275 1450);
DOT 1 (-9275 1650);
DOT 1 (-9275 1600);
DOT 1 (-9275 1550);
DOT 1 (-9275 1700);
DOT 1 (-9275 1750);
DOT 1 (-9275 1800);
DOT 1 (-9275 1900);
DOT 1 (-9275 1850);
DOT 1 (-9275 1950);
DOT 1 (-9275 2000);
DOT 1 (-9275 2050);
DOT 1 (-9275 2150);
DOT 1 (-9275 2100);
DOT 1 (-9275 2300);
DOT 1 (-9275 2250);
DOT 1 (-9275 2200);
DOT 1 (-9275 2350);
DOT 1 (-9275 2400);
DOT 1 (-9275 2550);
DOT 1 (-9275 2500);
DOT 1 (-9275 2450);
DOT 1 (-9275 2650);
DOT 1 (-9275 2600);
DOT 1 (-9275 2700);
DOT 1 (-9275 2800);
DOT 1 (-9275 2750);
DOT 1 (-9275 2850);
DOT 1 (-9275 2900);
DOT 1 (-9275 2950);
DOT 1 (-9275 3050);
DOT 1 (-9275 3000);
DOT 1 (-9275 3200);
DOT 1 (-9275 3250);
DOT 1 (-9275 3300);
DOT 1 (-9275 3450);
DOT 1 (-9275 3400);
DOT 1 (-9275 3350);
DOT 1 (-9275 3550);
DOT 1 (-9275 3500);
DOT 1 (-9275 3700);
DOT 1 (-9275 3650);
DOT 1 (-9275 3600);
DOT 1 (-9275 3750);
DOT 1 (-9275 3800);
DOT 1 (-9275 3850);
DOT 1 (-9275 3950);
DOT 1 (-9275 3900);
DOT 1 (-9275 4050);
DOT 1 (-9275 4000);
DOT 1 (-9275 4100);
DOT 1 (-9275 4200);
DOT 1 (-9275 4150);
DOT 1 (-9275 4350);
DOT 1 (-9275 4300);
DOT 1 (-9275 4250);
DOT 1 (-9275 4400);
DOT 1 (-9275 4450);
DOT 1 (-9275 4600);
DOT 1 (-9275 4550);
DOT 1 (-9275 4500);
DOT 1 (-9275 4700);
DOT 1 (-9275 4650);
DOT 1 (-9275 4850);
DOT 1 (-9275 4800);
DOT 1 (-9275 4750);
DOT 1 (-9275 4900);
DOT 1 (-9275 4950);
DOT 1 (-9275 5000);
DOT 1 (-9275 5100);
DOT 1 (-9275 5050);
DOT 1 (-9275 5200);
DOT 1 (-9275 5150);
DOT 1 (-9275 5250);
DOT 1 (-9275 5350);
DOT 1 (-9275 5300);
DOT 1 (-9275 5450);
DOT 1 (-9275 5400);
DOT 1 (-9275 5600);
DOT 1 (-9275 5550);
DOT 1 (-9275 5750);
DOT 1 (-9275 5700);
DOT 1 (-9275 5650);
DOT 1 (-9275 5800);
DOT 1 (-9275 5850);
DOT 1 (-9275 5900);
DOT 1 (-9275 6000);
DOT 1 (-9275 5950);
DOT 1 (-9275 6050);
DOT 1 (-9275 6100);
DOT 1 (-9275 6150);
DOT 1 (-9275 6200);
DOT 1 (-9275 6250);
DOT 1 (-9275 6300);
DOT 1 (-9275 650);
DOT 1 (-7925 450);
DOT 1 (-7925 500);
DOT 1 (-7925 950);
DOT 1 (-7925 1000);
DOT 1 (-7925 900);
DOT 1 (-7925 850);
DOT 1 (-7925 800);
DOT 1 (-7925 700);
DOT 1 (-7925 750);
DOT 1 (-7925 650);
DOT 1 (-7925 550);
DOT 1 (-7925 600);
DOT 1 (-7925 1300);
DOT 1 (-7925 1100);
DOT 1 (-7925 1500);
DOT 1 (-7925 1450);
DOT 1 (-7925 1400);
DOT 1 (-7925 1350);
DOT 1 (-7925 1250);
DOT 1 (-7925 1200);
DOT 1 (-7925 1150);
DOT 1 (-7925 1050);
DOT 1 (-7925 2000);
DOT 1 (-7925 1950);
DOT 1 (-7925 1850);
DOT 1 (-7925 1900);
DOT 1 (-7925 1800);
DOT 1 (-7925 1750);
DOT 1 (-7925 1700);
DOT 1 (-7925 1650);
DOT 1 (-7925 1550);
DOT 1 (-7925 1600);
DOT 1 (-7925 2050);
DOT 1 (-7925 2550);
DOT 1 (-7925 2450);
DOT 1 (-7925 2500);
DOT 1 (-7925 2400);
DOT 1 (-7925 2350);
DOT 1 (-7925 2300);
DOT 1 (-7925 2200);
DOT 1 (-7925 2250);
DOT 1 (-7925 2100);
DOT 1 (-7925 2150);
DOT 1 (-7925 3000);
DOT 1 (-7925 3050);
DOT 1 (-7925 2950);
DOT 1 (-7925 2900);
DOT 1 (-7925 2850);
DOT 1 (-7925 2750);
DOT 1 (-7925 2800);
DOT 1 (-7925 2700);
DOT 1 (-7925 2650);
DOT 1 (-7925 2600);
DOT 1 (-7925 3550);
DOT 1 (-7925 3500);
DOT 1 (-7925 3450);
DOT 1 (-7925 3350);
DOT 1 (-7925 3400);
DOT 1 (-7925 3300);
DOT 1 (-7925 3250);
DOT 1 (-7925 3200);
DOT 1 (-7925 3150);
DOT 1 (-7925 3100);
DOT 1 (-7925 4050);
DOT 1 (-7925 4000);
DOT 1 (-7925 3900);
DOT 1 (-7925 3950);
DOT 1 (-7925 3850);
DOT 1 (-7925 3800);
DOT 1 (-7925 3750);
DOT 1 (-7925 3700);
DOT 1 (-7925 3600);
DOT 1 (-7925 3650);
DOT 1 (-7925 4100);
DOT 1 (-7925 4600);
DOT 1 (-7925 4500);
DOT 1 (-7925 4550);
DOT 1 (-7925 4450);
DOT 1 (-7925 4400);
DOT 1 (-7925 4350);
DOT 1 (-7925 4250);
DOT 1 (-7925 4300);
DOT 1 (-7925 4150);
DOT 1 (-7925 4200);
DOT 1 (-7925 5050);
DOT 1 (-7925 5100);
DOT 1 (-7925 5000);
DOT 1 (-7925 4950);
DOT 1 (-7925 4900);
DOT 1 (-7925 4850);
DOT 1 (-7925 4750);
DOT 1 (-7925 4800);
DOT 1 (-7925 4700);
DOT 1 (-7925 4650);
DOT 1 (-7925 5600);
DOT 1 (-7925 5550);
DOT 1 (-7925 5500);
DOT 1 (-7925 5400);
DOT 1 (-7925 5450);
DOT 1 (-7925 5300);
DOT 1 (-7925 5350);
DOT 1 (-7925 5250);
DOT 1 (-7925 5200);
DOT 1 (-7925 5150);
DOT 1 (-7925 6100);
DOT 1 (-7925 6050);
DOT 1 (-7925 5950);
DOT 1 (-7925 5900);
DOT 1 (-7925 5800);
DOT 1 (-7925 5750);
DOT 1 (-7925 5650);
DOT 1 (-7925 5700);
DOT 1 (-7925 5850);
DOT 1 (-7925 6150);
DOT 1 (-7925 6300);
DOT 1 (-7925 6200);
DOT 1 (-7925 6250);
DOT 1 (-7925 6000);
DOT 1 (-9275 5500);
DOT 1 (-7750 475);
DOT 1 (-7750 525);
DOT 1 (-7750 575);
DOT 1 (-7750 625);
DOT 1 (-7750 725);
DOT 1 (-7750 675);
DOT 1 (-7750 775);
DOT 1 (-7750 825);
DOT 1 (-7750 875);
DOT 1 (-7750 975);
DOT 1 (-7750 925);
DOT 1 (-7750 1025);
DOT 1 (-7750 1075);
DOT 1 (-7750 1125);
DOT 1 (-7750 1175);
DOT 1 (-7750 1225);
DOT 1 (-7750 1275);
DOT 1 (-7750 1375);
DOT 1 (-7750 1325);
DOT 1 (-7750 1425);
DOT 1 (-7750 1475);
DOT 1 (-7750 1525);
DOT 1 (-7750 1625);
DOT 1 (-7750 1575);
DOT 1 (-7750 1675);
DOT 1 (-7750 1725);
DOT 1 (-7750 1775);
DOT 1 (-7750 1875);
DOT 1 (-7750 1825);
DOT 1 (-7750 1925);
DOT 1 (-7750 1975);
DOT 1 (-7750 2025);
DOT 1 (-6400 475);
DOT 1 (-6400 525);
DOT 1 (-6400 625);
DOT 1 (-6400 575);
DOT 1 (-6400 675);
DOT 1 (-6400 725);
DOT 1 (-6400 775);
DOT 1 (-6400 825);
DOT 1 (-6400 875);
DOT 1 (-6400 925);
DOT 1 (-6400 975);
DOT 1 (-6400 1025);
DOT 1 (-6400 1075);
DOT 1 (-6400 1125);
DOT 1 (-6400 1175);
DOT 1 (-6400 1225);
DOT 1 (-6400 1275);
DOT 1 (-6400 1375);
DOT 1 (-6400 1325);
DOT 1 (-6400 1425);
DOT 1 (-6400 1475);
DOT 1 (-6400 1525);
DOT 1 (-6400 1625);
DOT 1 (-6400 1575);
DOT 1 (-6400 1675);
DOT 1 (-6400 1725);
DOT 1 (-6400 1775);
DOT 1 (-6400 1825);
DOT 1 (-6400 1875);
DOT 1 (-6400 1925);
DOT 1 (-6400 1975);
DOT 1 (-6400 2025);
DOT 1 (-7750 2075);
DOT 1 (-7750 2125);
DOT 1 (-7750 2175);
DOT 1 (-7750 2275);
DOT 1 (-7750 2225);
DOT 1 (-7750 2325);
DOT 1 (-7750 2375);
DOT 1 (-7750 2425);
DOT 1 (-7750 2525);
DOT 1 (-7750 2475);
DOT 1 (-7750 2575);
DOT 1 (-7750 2625);
DOT 1 (-7750 2675);
DOT 1 (-7750 2775);
DOT 1 (-7750 2725);
DOT 1 (-7750 2825);
DOT 1 (-7750 2875);
DOT 1 (-7750 2925);
DOT 1 (-7750 3025);
DOT 1 (-7750 2975);
DOT 1 (-7750 3075);
DOT 1 (-7750 3125);
DOT 1 (-7750 3175);
DOT 1 (-7750 3225);
DOT 1 (-7750 3275);
DOT 1 (-7750 3325);
DOT 1 (-7750 3425);
DOT 1 (-7750 3375);
DOT 1 (-7750 3475);
DOT 1 (-7750 3525);
DOT 1 (-7750 3575);
DOT 1 (-7750 3675);
DOT 1 (-7750 3625);
DOT 1 (-7750 3725);
DOT 1 (-7750 3775);
DOT 1 (-7750 3825);
DOT 1 (-7750 3925);
DOT 1 (-7750 3875);
DOT 1 (-7750 3975);
DOT 1 (-7750 4025);
DOT 1 (-7750 4075);
DOT 1 (-6400 2175);
DOT 1 (-6400 2125);
DOT 1 (-6400 2075);
DOT 1 (-6400 2275);
DOT 1 (-6400 2225);
DOT 1 (-6400 2325);
DOT 1 (-6400 2375);
DOT 1 (-6400 2425);
DOT 1 (-6400 2525);
DOT 1 (-6400 2475);
DOT 1 (-6400 2625);
DOT 1 (-6400 2675);
DOT 1 (-6400 2575);
DOT 1 (-6400 2725);
DOT 1 (-6400 2775);
DOT 1 (-6400 2825);
DOT 1 (-6400 2875);
DOT 1 (-6400 2925);
DOT 1 (-6400 2975);
DOT 1 (-6400 3025);
DOT 1 (-6400 3075);
DOT 1 (-6400 3125);
DOT 1 (-6400 3175);
DOT 1 (-6400 3225);
DOT 1 (-6400 3275);
DOT 1 (-6400 3325);
DOT 1 (-6400 3375);
DOT 1 (-6400 3425);
DOT 1 (-6400 3475);
DOT 1 (-6400 3525);
DOT 1 (-6400 3575);
DOT 1 (-6400 3675);
DOT 1 (-6400 3625);
DOT 1 (-6400 3725);
DOT 1 (-6400 3775);
DOT 1 (-6400 3825);
DOT 1 (-6400 3875);
DOT 1 (-6400 3925);
DOT 1 (-6400 3975);
DOT 1 (-6400 4025);
DOT 1 (-6400 4075);
DOT 1 (-7750 4175);
DOT 1 (-7750 4125);
DOT 1 (-7750 4225);
DOT 1 (-7750 4275);
DOT 1 (-7750 4325);
DOT 1 (-7750 4375);
DOT 1 (-7750 4475);
DOT 1 (-7750 4575);
DOT 1 (-7750 4525);
DOT 1 (-7750 4625);
DOT 1 (-7750 4675);
DOT 1 (-7750 4725);
DOT 1 (-7750 4825);
DOT 1 (-7750 4775);
DOT 1 (-7750 4875);
DOT 1 (-7750 4925);
DOT 1 (-7750 4975);
DOT 1 (-7750 5025);
DOT 1 (-7750 5075);
DOT 1 (-7750 5125);
DOT 1 (-7750 5175);
DOT 1 (-7750 5225);
DOT 1 (-7750 5275);
DOT 1 (-7750 5325);
DOT 1 (-7750 5375);
DOT 1 (-7750 5475);
DOT 1 (-7750 5525);
DOT 1 (-7750 5575);
DOT 1 (-7750 5625);
DOT 1 (-7750 5725);
DOT 1 (-7750 5675);
DOT 1 (-7750 5775);
DOT 1 (-7750 5825);
DOT 1 (-7750 5875);
DOT 1 (-7750 5925);
DOT 1 (-7750 5975);
DOT 1 (-7750 6025);
DOT 1 (-7750 6125);
DOT 1 (-7750 6075);
DOT 1 (-6400 4175);
DOT 1 (-6400 4125);
DOT 1 (-6400 4225);
DOT 1 (-6400 4325);
DOT 1 (-6400 4275);
DOT 1 (-6400 4375);
DOT 1 (-6400 4425);
DOT 1 (-6400 4475);
DOT 1 (-6400 4575);
DOT 1 (-6400 4525);
DOT 1 (-6400 4675);
DOT 1 (-6400 4725);
DOT 1 (-6400 4625);
DOT 1 (-6400 4825);
DOT 1 (-6400 4775);
DOT 1 (-6400 4875);
DOT 1 (-6400 4925);
DOT 1 (-6400 4975);
DOT 1 (-6400 5025);
DOT 1 (-6400 5075);
DOT 1 (-6400 5125);
DOT 1 (-6400 5175);
DOT 1 (-6400 5225);
DOT 1 (-6400 5275);
DOT 1 (-6400 5375);
DOT 1 (-6400 5325);
DOT 1 (-6400 5475);
DOT 1 (-6400 5425);
DOT 1 (-6400 5525);
DOT 1 (-6400 5575);
DOT 1 (-6400 5625);
DOT 1 (-6400 5725);
DOT 1 (-6400 5675);
DOT 1 (-6400 5775);
DOT 1 (-6400 5825);
DOT 1 (-6400 5875);
DOT 1 (-6400 5925);
DOT 1 (-6400 5975);
DOT 1 (-6400 6025);
DOT 1 (-6400 6075);
DOT 1 (-6400 6125);
DOT 1 (-7750 6175);
DOT 1 (-7750 6225);
DOT 1 (-6400 6225);
DOT 1 (-6400 6175);
DOT 1 (-7750 5425);
DOT 1 (-7750 4425);
DOT 1 (-6275 500);
DOT 1 (-6275 600);
DOT 1 (-6275 550);
DOT 1 (-6275 650);
DOT 1 (-6275 750);
DOT 1 (-6275 700);
DOT 1 (-6275 850);
DOT 1 (-6275 800);
DOT 1 (-6275 900);
DOT 1 (-6275 1000);
DOT 1 (-6275 950);
DOT 1 (-6275 1150);
DOT 1 (-6275 1100);
DOT 1 (-6275 1050);
DOT 1 (-6275 1250);
DOT 1 (-6275 1200);
DOT 1 (-6275 1400);
DOT 1 (-6275 1350);
DOT 1 (-6275 1300);
DOT 1 (-6275 1500);
DOT 1 (-6275 1450);
DOT 1 (-6275 1550);
DOT 1 (-6275 1600);
DOT 1 (-6275 1650);
DOT 1 (-6275 1750);
DOT 1 (-6275 1700);
DOT 1 (-6275 1800);
DOT 1 (-6275 1900);
DOT 1 (-6275 1850);
DOT 1 (-6275 2000);
DOT 1 (-6275 1950);
DOT 1 (-6275 2050);
DOT 1 (-6275 2150);
DOT 1 (-6275 2100);
DOT 1 (-6275 2300);
DOT 1 (-6275 2250);
DOT 1 (-6275 2200);
DOT 1 (-6275 2400);
DOT 1 (-6275 2350);
DOT 1 (-6275 2550);
DOT 1 (-6275 2500);
DOT 1 (-6275 2450);
DOT 1 (-6275 2650);
DOT 1 (-6275 2600);
DOT 1 (-6275 2700);
DOT 1 (-6275 2800);
DOT 1 (-6275 2750);
DOT 1 (-6275 2900);
DOT 1 (-6275 2850);
DOT 1 (-6275 2950);
DOT 1 (-6275 3050);
DOT 1 (-6275 3000);
DOT 1 (-6275 3150);
DOT 1 (-6275 3100);
DOT 1 (-6275 3200);
DOT 1 (-6275 3300);
DOT 1 (-6275 3250);
DOT 1 (-6275 3450);
DOT 1 (-6275 3400);
DOT 1 (-6275 3350);
DOT 1 (-6275 3550);
DOT 1 (-6275 3500);
DOT 1 (-6275 3700);
DOT 1 (-6275 3650);
DOT 1 (-6275 3600);
DOT 1 (-6275 3800);
DOT 1 (-6275 3750);
DOT 1 (-6275 3850);
DOT 1 (-6275 3950);
DOT 1 (-6275 3900);
DOT 1 (-6275 4000);
DOT 1 (-4925 550);
DOT 1 (-4925 600);
DOT 1 (-4925 650);
DOT 1 (-4925 700);
DOT 1 (-4925 750);
DOT 1 (-4925 850);
DOT 1 (-4925 800);
DOT 1 (-4925 900);
DOT 1 (-4925 1000);
DOT 1 (-4925 950);
DOT 1 (-4925 1150);
DOT 1 (-4925 1050);
DOT 1 (-4925 1100);
DOT 1 (-4925 1250);
DOT 1 (-4925 1200);
DOT 1 (-4925 1300);
DOT 1 (-4925 1350);
DOT 1 (-4925 1400);
DOT 1 (-4925 1450);
DOT 1 (-4925 1500);
DOT 1 (-4925 1650);
DOT 1 (-4925 1600);
DOT 1 (-4925 1550);
DOT 1 (-4925 1750);
DOT 1 (-4925 1700);
DOT 1 (-4925 1800);
DOT 1 (-4925 1850);
DOT 1 (-4925 1900);
DOT 1 (-4925 2000);
DOT 1 (-4925 1950);
DOT 1 (-4925 2050);
DOT 1 (-4925 2100);
DOT 1 (-4925 2150);
DOT 1 (-4925 2250);
DOT 1 (-4925 2200);
DOT 1 (-4925 2300);
DOT 1 (-4925 2400);
DOT 1 (-4925 2350);
DOT 1 (-4925 2550);
DOT 1 (-4925 2500);
DOT 1 (-4925 2450);
DOT 1 (-4925 2600);
DOT 1 (-4925 2650);
DOT 1 (-4925 2700);
DOT 1 (-4925 2800);
DOT 1 (-4925 2750);
DOT 1 (-4925 2850);
DOT 1 (-4925 2900);
DOT 1 (-4925 2950);
DOT 1 (-4925 3050);
DOT 1 (-4925 3000);
DOT 1 (-4925 3150);
DOT 1 (-4925 3100);
DOT 1 (-4925 3200);
DOT 1 (-4925 3250);
DOT 1 (-4925 3300);
DOT 1 (-4925 3350);
DOT 1 (-4925 3400);
DOT 1 (-4925 3450);
DOT 1 (-4925 3500);
DOT 1 (-4925 3550);
DOT 1 (-4925 3650);
DOT 1 (-4925 3600);
DOT 1 (-4925 3700);
DOT 1 (-4925 3800);
DOT 1 (-4925 3750);
DOT 1 (-4925 3850);
DOT 1 (-4925 3900);
DOT 1 (-4925 3950);
DOT 1 (-4925 4050);
DOT 1 (-4925 4000);
DOT 1 (-6275 4100);
DOT 1 (-4925 4100);
DOT 1 (-6275 4150);
DOT 1 (-6275 4200);
DOT 1 (-6275 4300);
DOT 1 (-6275 4350);
DOT 1 (-6275 4250);
DOT 1 (-6275 4450);
DOT 1 (-6275 4400);
DOT 1 (-6275 4550);
DOT 1 (-6275 4600);
DOT 1 (-6275 4500);
DOT 1 (-6275 4700);
DOT 1 (-6275 4650);
DOT 1 (-6275 4750);
DOT 1 (-6275 4800);
DOT 1 (-6275 4850);
DOT 1 (-6275 4900);
DOT 1 (-6275 4950);
DOT 1 (-6275 5000);
DOT 1 (-6275 5050);
DOT 1 (-6275 5100);
DOT 1 (-6275 5150);
DOT 1 (-6275 5200);
DOT 1 (-6275 5250);
DOT 1 (-6275 5350);
DOT 1 (-6275 5300);
DOT 1 (-6275 5500);
DOT 1 (-6275 5450);
DOT 1 (-6275 5400);
DOT 1 (-6275 5600);
DOT 1 (-6275 5550);
DOT 1 (-6275 5750);
DOT 1 (-6275 5700);
DOT 1 (-6275 5650);
DOT 1 (-6275 5850);
DOT 1 (-6275 5800);
DOT 1 (-6275 5900);
DOT 1 (-6275 6000);
DOT 1 (-6275 5950);
DOT 1 (-6275 6100);
DOT 1 (-6275 6050);
DOT 1 (-6275 6150);
DOT 1 (-6275 6250);
DOT 1 (-6275 6200);
DOT 1 (-4925 4150);
DOT 1 (-4925 4200);
DOT 1 (-4925 4300);
DOT 1 (-4925 4250);
DOT 1 (-4925 4350);
DOT 1 (-4925 4450);
DOT 1 (-4925 4400);
DOT 1 (-4925 4600);
DOT 1 (-4925 4550);
DOT 1 (-4925 4500);
DOT 1 (-4925 4650);
DOT 1 (-4925 4700);
DOT 1 (-4925 4750);
DOT 1 (-4925 4800);
DOT 1 (-4925 4850);
DOT 1 (-4925 4950);
DOT 1 (-4925 4900);
DOT 1 (-4925 5000);
DOT 1 (-4925 5100);
DOT 1 (-4925 5050);
DOT 1 (-4925 5200);
DOT 1 (-4925 5150);
DOT 1 (-4925 5250);
DOT 1 (-4925 5300);
DOT 1 (-4925 5350);
DOT 1 (-4925 5450);
DOT 1 (-4925 5400);
DOT 1 (-4925 5500);
DOT 1 (-4925 5550);
DOT 1 (-4925 5600);
DOT 1 (-4925 5700);
DOT 1 (-4925 5650);
DOT 1 (-4925 5750);
DOT 1 (-4925 5850);
DOT 1 (-4925 5800);
DOT 1 (-4925 5900);
DOT 1 (-4925 5950);
DOT 1 (-4925 6000);
DOT 1 (-4925 6100);
DOT 1 (-4925 6050);
DOT 1 (-4925 6150);
DOT 1 (-4925 6200);
DOT 1 (-4925 6250);
DOT 1 (-4775 575);
DOT 1 (-4775 625);
DOT 1 (-4775 725);
DOT 1 (-4775 675);
DOT 1 (-4775 775);
DOT 1 (-4775 825);
DOT 1 (-4775 875);
DOT 1 (-4775 925);
DOT 1 (-4775 975);
DOT 1 (-4775 1025);
DOT 1 (-4775 1075);
DOT 1 (-4775 1125);
DOT 1 (-4775 1175);
DOT 1 (-4775 1225);
DOT 1 (-4775 1275);
DOT 1 (-4775 1325);
DOT 1 (-4775 1375);
DOT 1 (-4775 1425);
DOT 1 (-4775 1475);
DOT 1 (-4775 1525);
DOT 1 (-4775 1575);
DOT 1 (-4775 1625);
DOT 1 (-4775 1675);
DOT 1 (-4775 1725);
DOT 1 (-4775 1775);
DOT 1 (-4775 1825);
DOT 1 (-4775 1875);
DOT 1 (-4775 1925);
DOT 1 (-4775 1975);
DOT 1 (-4775 2025);
DOT 1 (-4775 2075);
DOT 1 (-4775 2125);
DOT 1 (-4775 2175);
DOT 1 (-4775 2225);
DOT 1 (-4775 2275);
DOT 1 (-4775 2325);
DOT 1 (-4775 2375);
DOT 1 (-4775 2425);
DOT 1 (-4775 2475);
DOT 1 (-4775 2525);
DOT 1 (-4775 2575);
DOT 1 (-4775 2625);
DOT 1 (-4775 2675);
DOT 1 (-4775 2725);
DOT 1 (-4775 2775);
DOT 1 (-4775 2825);
DOT 1 (-4775 2875);
DOT 1 (-4775 2925);
DOT 1 (-4775 2975);
DOT 1 (-4775 3025);
DOT 1 (-4775 3075);
DOT 1 (-4775 3125);
DOT 1 (-4775 3175);
DOT 1 (-4775 3225);
DOT 1 (-4775 3275);
DOT 1 (-4775 3325);
DOT 1 (-4775 3375);
DOT 1 (-4775 3425);
DOT 1 (-4775 3475);
DOT 1 (-4775 3525);
DOT 1 (-4775 3575);
DOT 1 (-4775 3625);
DOT 1 (-4775 3675);
DOT 1 (-4775 3725);
DOT 1 (-4775 3775);
DOT 1 (-4775 3825);
DOT 1 (-4775 3875);
DOT 1 (-4775 3925);
DOT 1 (-4775 3975);
DOT 1 (-4775 4025);
DOT 1 (-4775 4075);
DOT 1 (-4775 4125);
DOT 1 (-4775 4175);
DOT 1 (-4775 4225);
DOT 1 (-4775 4275);
DOT 1 (-4775 4325);
DOT 1 (-4775 4375);
DOT 1 (-4775 4425);
DOT 1 (-4775 4475);
DOT 1 (-4775 4525);
DOT 1 (-4775 4575);
DOT 1 (-4775 4625);
DOT 1 (-4775 4675);
DOT 1 (-4775 4725);
DOT 1 (-4775 4775);
DOT 1 (-4775 4825);
DOT 1 (-4775 4875);
DOT 1 (-4775 4925);
DOT 1 (-4775 4975);
DOT 1 (-4775 5025);
DOT 1 (-4775 5075);
DOT 1 (-4775 5125);
DOT 1 (-4775 5175);
DOT 1 (-4775 5225);
DOT 1 (-4775 5275);
DOT 1 (-4775 5325);
DOT 1 (-4775 5375);
DOT 1 (-4775 5425);
DOT 1 (-4775 5475);
DOT 1 (-4775 5525);
DOT 1 (-4775 5575);
DOT 1 (-4775 5625);
DOT 1 (-4775 5675);
DOT 1 (-4775 5725);
DOT 1 (-4775 5775);
DOT 1 (-4775 5825);
DOT 1 (-4775 5875);
DOT 1 (-4775 5925);
DOT 1 (-4775 5975);
DOT 1 (-4775 6025);
DOT 1 (-4775 6075);
DOT 1 (-4775 6125);
DOT 1 (-4775 6175);
DOT 1 (-4775 6225);
DOT 1 (-4775 6275);
DOT 1 (-4775 6325);
DOT 1 (-3425 575);
DOT 1 (-3425 625);
DOT 1 (-3425 675);
DOT 1 (-3425 725);
DOT 1 (-3425 775);
DOT 1 (-3425 825);
DOT 1 (-3425 875);
DOT 1 (-3425 925);
DOT 1 (-3425 975);
DOT 1 (-3425 1025);
DOT 1 (-3425 1075);
DOT 1 (-3425 1125);
DOT 1 (-3425 1175);
DOT 1 (-3425 1225);
DOT 1 (-3425 1275);
DOT 1 (-3425 1375);
DOT 1 (-3425 1325);
DOT 1 (-3425 1425);
DOT 1 (-3425 1475);
DOT 1 (-3425 1525);
DOT 1 (-3425 1575);
DOT 1 (-3425 1625);
DOT 1 (-3425 1675);
DOT 1 (-3425 1725);
DOT 1 (-3425 1775);
DOT 1 (-3425 1875);
DOT 1 (-3425 1825);
DOT 1 (-3425 1925);
DOT 1 (-3425 1975);
DOT 1 (-3425 2025);
DOT 1 (-3425 2075);
DOT 1 (-3425 2125);
DOT 1 (-3425 2175);
DOT 1 (-3425 2225);
DOT 1 (-3425 2275);
DOT 1 (-3425 2325);
DOT 1 (-3425 2375);
DOT 1 (-3425 2425);
DOT 1 (-3425 2475);
DOT 1 (-3425 2525);
DOT 1 (-3425 2575);
DOT 1 (-3425 2625);
DOT 1 (-3425 2675);
DOT 1 (-3425 2775);
DOT 1 (-3425 2725);
DOT 1 (-3425 2825);
DOT 1 (-3425 2875);
DOT 1 (-3425 2925);
DOT 1 (-3425 2975);
DOT 1 (-3425 3025);
DOT 1 (-3425 3075);
DOT 1 (-3425 3125);
DOT 1 (-3425 3175);
DOT 1 (-3425 3225);
DOT 1 (-3425 3275);
DOT 1 (-3425 3325);
DOT 1 (-3425 3425);
DOT 1 (-3425 3375);
DOT 1 (-3425 3475);
DOT 1 (-3425 3525);
DOT 1 (-3425 3575);
DOT 1 (-3425 3625);
DOT 1 (-3425 3675);
DOT 1 (-3425 3775);
DOT 1 (-3425 3825);
DOT 1 (-3425 3925);
DOT 1 (-3425 3875);
DOT 1 (-3425 3975);
DOT 1 (-3425 4025);
DOT 1 (-3425 4075);
DOT 1 (-3425 4125);
DOT 1 (-3425 4175);
DOT 1 (-3425 4225);
DOT 1 (-3425 4275);
DOT 1 (-3425 4325);
DOT 1 (-3425 4375);
DOT 1 (-3425 4425);
DOT 1 (-3425 4475);
DOT 1 (-3425 4525);
DOT 1 (-3425 4575);
DOT 1 (-3425 4625);
DOT 1 (-3425 4675);
DOT 1 (-3425 4725);
DOT 1 (-3425 4825);
DOT 1 (-3425 4775);
DOT 1 (-3425 4875);
DOT 1 (-3425 4925);
DOT 1 (-3425 4975);
DOT 1 (-3425 5025);
DOT 1 (-3425 5075);
DOT 1 (-3425 5125);
DOT 1 (-3425 5175);
DOT 1 (-3425 5225);
DOT 1 (-3425 5275);
DOT 1 (-3425 5325);
DOT 1 (-3425 5375);
DOT 1 (-3425 5425);
DOT 1 (-3425 5475);
DOT 1 (-3425 5525);
DOT 1 (-3425 5575);
DOT 1 (-3425 5625);
DOT 1 (-3425 5675);
DOT 1 (-3425 5725);
DOT 1 (-3425 5775);
DOT 1 (-3425 5825);
DOT 1 (-3425 5875);
DOT 1 (-3425 5975);
DOT 1 (-3425 5925);
DOT 1 (-3425 6025);
DOT 1 (-3425 6075);
DOT 1 (-3425 6125);
DOT 1 (-3425 6175);
DOT 1 (-3425 6225);
DOT 1 (-3425 6275);
DOT 1 (-3425 6325);
DOT 1 (-6275 4050);
DOT 1 (-3425 3725);
DOT 1 (-3275 525);
DOT 1 (-3275 575);
DOT 1 (-3275 625);
DOT 1 (-3275 675);
DOT 1 (-3275 725);
DOT 1 (-3275 775);
DOT 1 (-3275 825);
DOT 1 (-3275 875);
DOT 1 (-3275 925);
DOT 1 (-3275 975);
DOT 1 (-3275 1025);
DOT 1 (-3275 1075);
DOT 1 (-3275 1125);
DOT 1 (-3275 1275);
DOT 1 (-3275 1225);
DOT 1 (-3275 1175);
DOT 1 (-3275 1325);
DOT 1 (-3275 1375);
DOT 1 (-3275 1525);
DOT 1 (-3275 1475);
DOT 1 (-3275 1425);
DOT 1 (-3275 1575);
DOT 1 (-3275 1625);
DOT 1 (-3275 1675);
DOT 1 (-3275 1775);
DOT 1 (-3275 1725);
DOT 1 (-3275 1825);
DOT 1 (-3275 1875);
DOT 1 (-3275 1925);
DOT 1 (-3275 2025);
DOT 1 (-3275 1975);
DOT 1 (-3275 2075);
DOT 1 (-3275 2125);
DOT 1 (-3275 2175);
DOT 1 (-3275 2225);
DOT 1 (-3275 2275);
DOT 1 (-3275 2325);
DOT 1 (-3275 2375);
DOT 1 (-3275 2425);
DOT 1 (-3275 2475);
DOT 1 (-3275 2525);
DOT 1 (-3275 2575);
DOT 1 (-3275 2625);
DOT 1 (-3275 2675);
DOT 1 (-3275 2725);
DOT 1 (-3275 2775);
DOT 1 (-3275 2825);
DOT 1 (-3275 2875);
DOT 1 (-3275 2925);
DOT 1 (-3275 2975);
DOT 1 (-3275 3025);
DOT 1 (-3275 3075);
DOT 1 (-3275 3125);
DOT 1 (-3275 3175);
DOT 1 (-3275 3325);
DOT 1 (-3275 3275);
DOT 1 (-3275 3225);
DOT 1 (-3275 3375);
DOT 1 (-3275 3425);
DOT 1 (-3275 3575);
DOT 1 (-3275 3525);
DOT 1 (-3275 3475);
DOT 1 (-3275 3625);
DOT 1 (-3275 3675);
DOT 1 (-3275 3725);
DOT 1 (-3275 3775);
DOT 1 (-3275 3875);
DOT 1 (-3275 3925);
DOT 1 (-3275 3975);
DOT 1 (-3275 4075);
DOT 1 (-3275 4025);
DOT 1 (-1950 575);
DOT 1 (-1950 675);
DOT 1 (-1950 775);
DOT 1 (-1950 875);
DOT 1 (-1950 975);
DOT 1 (-1950 1025);
DOT 1 (-1950 1075);
DOT 1 (-1950 1125);
DOT 1 (-1950 1175);
DOT 1 (-1950 1225);
DOT 1 (-1950 1275);
DOT 1 (-1950 1375);
DOT 1 (-1950 1325);
DOT 1 (-1950 1425);
DOT 1 (-1950 1475);
DOT 1 (-1950 1525);
DOT 1 (-1950 1575);
DOT 1 (-1950 1625);
DOT 1 (-1950 1675);
DOT 1 (-1950 1725);
DOT 1 (-1950 1775);
DOT 1 (-1950 1875);
DOT 1 (-1950 1825);
DOT 1 (-1950 1925);
DOT 1 (-1950 1975);
DOT 1 (-1950 2025);
DOT 1 (-1950 2075);
DOT 1 (-1950 2125);
DOT 1 (-1950 2175);
DOT 1 (-1950 2275);
DOT 1 (-1950 2225);
DOT 1 (-1950 2325);
DOT 1 (-1950 2375);
DOT 1 (-1950 2425);
DOT 1 (-1950 2525);
DOT 1 (-1950 2475);
DOT 1 (-1950 2575);
DOT 1 (-1950 2625);
DOT 1 (-1950 2675);
DOT 1 (-1950 2775);
DOT 1 (-1950 2725);
DOT 1 (-1950 2825);
DOT 1 (-1950 2875);
DOT 1 (-1950 2925);
DOT 1 (-1950 3025);
DOT 1 (-1950 2975);
DOT 1 (-1950 3075);
DOT 1 (-1950 3125);
DOT 1 (-1950 3175);
DOT 1 (-1950 3225);
DOT 1 (-1950 3275);
DOT 1 (-1950 3325);
DOT 1 (-1950 3425);
DOT 1 (-1950 3375);
DOT 1 (-1950 3475);
DOT 1 (-1950 3525);
DOT 1 (-1950 3575);
DOT 1 (-1950 3625);
DOT 1 (-1950 3675);
DOT 1 (-1950 3725);
DOT 1 (-1950 3775);
DOT 1 (-1950 3825);
DOT 1 (-1950 3925);
DOT 1 (-1950 3875);
DOT 1 (-1950 3975);
DOT 1 (-1950 4025);
DOT 1 (-1950 4075);
DOT 1 (-3275 4125);
DOT 1 (-3275 4175);
DOT 1 (-3275 4225);
DOT 1 (-3275 4325);
DOT 1 (-3275 4275);
DOT 1 (-3275 4375);
DOT 1 (-3275 4425);
DOT 1 (-3275 4475);
DOT 1 (-3275 4525);
DOT 1 (-3275 4575);
DOT 1 (-3275 4625);
DOT 1 (-3275 4675);
DOT 1 (-3275 4725);
DOT 1 (-3275 4775);
DOT 1 (-3275 4825);
DOT 1 (-3275 4875);
DOT 1 (-3275 4925);
DOT 1 (-3275 4975);
DOT 1 (-3275 5025);
DOT 1 (-3275 5075);
DOT 1 (-3275 5125);
DOT 1 (-3275 5175);
DOT 1 (-3275 5225);
DOT 1 (-3275 5375);
DOT 1 (-3275 5325);
DOT 1 (-3275 5275);
DOT 1 (-3275 5425);
DOT 1 (-3275 5475);
DOT 1 (-3275 5625);
DOT 1 (-3275 5575);
DOT 1 (-3275 5525);
DOT 1 (-3275 5675);
DOT 1 (-3275 5725);
DOT 1 (-3275 5875);
DOT 1 (-3275 5825);
DOT 1 (-3275 5775);
DOT 1 (-3275 5925);
DOT 1 (-3275 5975);
DOT 1 (-3275 6025);
DOT 1 (-3275 6125);
DOT 1 (-3275 6075);
DOT 1 (-3275 6225);
DOT 1 (-3275 6175);
DOT 1 (-3275 6275);
DOT 1 (-3275 6325);
DOT 1 (-1950 4175);
DOT 1 (-1950 4125);
DOT 1 (-1950 4225);
DOT 1 (-1950 4275);
DOT 1 (-1950 4325);
DOT 1 (-1950 4375);
DOT 1 (-1950 4425);
DOT 1 (-1950 4475);
DOT 1 (-1950 4575);
DOT 1 (-1950 4525);
DOT 1 (-1950 4625);
DOT 1 (-1950 4675);
DOT 1 (-1950 4725);
DOT 1 (-1950 4825);
DOT 1 (-1950 4775);
DOT 1 (-1950 4875);
DOT 1 (-1950 4925);
DOT 1 (-1950 4975);
DOT 1 (-1950 5075);
DOT 1 (-1950 5025);
DOT 1 (-1950 5125);
DOT 1 (-1950 5175);
DOT 1 (-1950 5225);
DOT 1 (-1950 5275);
DOT 1 (-1950 5325);
DOT 1 (-1950 5375);
DOT 1 (-1950 5475);
DOT 1 (-1950 5425);
DOT 1 (-1950 5525);
DOT 1 (-1950 5575);
DOT 1 (-1950 5625);
DOT 1 (-1950 5675);
DOT 1 (-1950 5725);
DOT 1 (-1950 5775);
DOT 1 (-1950 5825);
DOT 1 (-1950 5875);
DOT 1 (-1950 5975);
DOT 1 (-1950 5925);
DOT 1 (-1950 6025);
DOT 1 (-1950 6075);
DOT 1 (-1950 6125);
DOT 1 (-1950 6225);
DOT 1 (-1950 6175);
DOT 1 (-1950 6275);
DOT 1 (-1950 6325);
DOT 1 (-1950 6375);
DOT 1 (-1950 525);
DOT 1 (-1950 625);
DOT 1 (-1950 725);
DOT 1 (-1950 825);
DOT 1 (-1950 925);
DOT 1 (-3275 3825);
DOT 1 (-1650 625);
DOT 1 (-1650 725);
DOT 1 (-1650 675);
DOT 1 (-1650 775);
DOT 1 (-1650 825);
DOT 1 (-1650 875);
DOT 1 (-1650 975);
DOT 1 (-1650 925);
DOT 1 (-1650 1025);
DOT 1 (-1650 1075);
DOT 1 (-1650 1125);
DOT 1 (-1650 1175);
DOT 1 (-1650 1225);
DOT 1 (-1650 1275);
DOT 1 (-1650 1375);
DOT 1 (-1650 1325);
DOT 1 (-1650 1425);
DOT 1 (-1650 1475);
DOT 1 (-1650 1525);
DOT 1 (-1650 1625);
DOT 1 (-1650 1575);
DOT 1 (-1650 1675);
DOT 1 (-1650 1725);
DOT 1 (-1650 1775);
DOT 1 (-1650 1875);
DOT 1 (-1650 1825);
DOT 1 (-1650 1925);
DOT 1 (-1650 1975);
DOT 1 (-1650 2025);
DOT 1 (-325 525);
DOT 1 (-325 625);
DOT 1 (-325 575);
DOT 1 (-325 725);
DOT 1 (-325 675);
DOT 1 (-325 775);
DOT 1 (-325 875);
DOT 1 (-325 825);
DOT 1 (-325 925);
DOT 1 (-325 975);
DOT 1 (-325 1025);
DOT 1 (-325 1125);
DOT 1 (-325 1075);
DOT 1 (-325 1275);
DOT 1 (-325 1225);
DOT 1 (-325 1175);
DOT 1 (-325 1375);
DOT 1 (-325 1325);
DOT 1 (-325 1475);
DOT 1 (-325 1525);
DOT 1 (-325 1425);
DOT 1 (-325 1625);
DOT 1 (-325 1575);
DOT 1 (-325 1675);
DOT 1 (-325 1775);
DOT 1 (-325 1725);
DOT 1 (-325 1875);
DOT 1 (-325 1825);
DOT 1 (-325 1925);
DOT 1 (-325 2025);
DOT 1 (-325 1975);
DOT 1 (-1650 2075);
DOT 1 (-1650 2125);
DOT 1 (-1650 2175);
DOT 1 (-1650 2275);
DOT 1 (-1650 2225);
DOT 1 (-1650 2325);
DOT 1 (-1650 2375);
DOT 1 (-1650 2425);
DOT 1 (-1650 2525);
DOT 1 (-1650 2475);
DOT 1 (-1650 2575);
DOT 1 (-1650 2625);
DOT 1 (-1650 2675);
DOT 1 (-1650 2775);
DOT 1 (-1650 2725);
DOT 1 (-1650 2825);
DOT 1 (-1650 2875);
DOT 1 (-1650 2925);
DOT 1 (-1650 3025);
DOT 1 (-1650 2975);
DOT 1 (-1650 3075);
DOT 1 (-1650 3125);
DOT 1 (-1650 3175);
DOT 1 (-1650 3225);
DOT 1 (-1650 3275);
DOT 1 (-1650 3325);
DOT 1 (-1650 3425);
DOT 1 (-1650 3375);
DOT 1 (-1650 3475);
DOT 1 (-1650 3525);
DOT 1 (-1650 3575);
DOT 1 (-1650 3675);
DOT 1 (-1650 3625);
DOT 1 (-1650 3725);
DOT 1 (-1650 3775);
DOT 1 (-1650 3825);
DOT 1 (-1650 3925);
DOT 1 (-1650 3875);
DOT 1 (-1650 3975);
DOT 1 (-1650 4025);
DOT 1 (-1650 4075);
DOT 1 (-325 2175);
DOT 1 (-325 2125);
DOT 1 (-325 2075);
DOT 1 (-325 2275);
DOT 1 (-325 2225);
DOT 1 (-325 2425);
DOT 1 (-325 2375);
DOT 1 (-325 2325);
DOT 1 (-325 2475);
DOT 1 (-325 2525);
DOT 1 (-325 2625);
DOT 1 (-325 2675);
DOT 1 (-325 2575);
DOT 1 (-325 2725);
DOT 1 (-325 2775);
DOT 1 (-325 2825);
DOT 1 (-325 2925);
DOT 1 (-325 2875);
DOT 1 (-325 2975);
DOT 1 (-325 3025);
DOT 1 (-325 3075);
DOT 1 (-325 3175);
DOT 1 (-325 3125);
DOT 1 (-325 3275);
DOT 1 (-325 3325);
DOT 1 (-325 3225);
DOT 1 (-325 3425);
DOT 1 (-325 3375);
DOT 1 (-325 3525);
DOT 1 (-325 3575);
DOT 1 (-325 3475);
DOT 1 (-325 3675);
DOT 1 (-325 3625);
DOT 1 (-325 3725);
DOT 1 (-325 3825);
DOT 1 (-325 3775);
DOT 1 (-325 3925);
DOT 1 (-325 3875);
DOT 1 (-325 3975);
DOT 1 (-325 4075);
DOT 1 (-325 4025);
DOT 1 (-1650 4175);
DOT 1 (-1650 4125);
DOT 1 (-1650 4225);
DOT 1 (-1650 4275);
DOT 1 (-1650 4325);
DOT 1 (-1650 4375);
DOT 1 (-1650 4425);
DOT 1 (-1650 4475);
DOT 1 (-1650 4575);
DOT 1 (-1650 4525);
DOT 1 (-1650 4625);
DOT 1 (-1650 4675);
DOT 1 (-1650 4725);
DOT 1 (-1650 4825);
DOT 1 (-1650 4775);
DOT 1 (-1650 4875);
DOT 1 (-1650 4925);
DOT 1 (-1650 4975);
DOT 1 (-1650 5075);
DOT 1 (-1650 5025);
DOT 1 (-1650 5125);
DOT 1 (-1650 5175);
DOT 1 (-1650 5225);
DOT 1 (-1650 5275);
DOT 1 (-1650 5325);
DOT 1 (-1650 5375);
DOT 1 (-1650 5475);
DOT 1 (-1650 5425);
DOT 1 (-1650 5525);
DOT 1 (-1650 5575);
DOT 1 (-1650 5625);
DOT 1 (-1650 5725);
DOT 1 (-1650 5675);
DOT 1 (-1650 5775);
DOT 1 (-1650 5825);
DOT 1 (-1650 5875);
DOT 1 (-1650 5975);
DOT 1 (-1650 5925);
DOT 1 (-1650 6025);
DOT 1 (-1650 6075);
DOT 1 (-1650 6125);
DOT 1 (-325 4175);
DOT 1 (-325 4125);
DOT 1 (-325 4225);
DOT 1 (-325 4325);
DOT 1 (-325 4275);
DOT 1 (-325 4475);
DOT 1 (-325 4425);
DOT 1 (-325 4375);
DOT 1 (-325 4525);
DOT 1 (-325 4575);
DOT 1 (-325 4675);
DOT 1 (-325 4725);
DOT 1 (-325 4625);
DOT 1 (-325 4775);
DOT 1 (-325 4825);
DOT 1 (-325 4875);
DOT 1 (-325 4975);
DOT 1 (-325 4925);
DOT 1 (-325 5025);
DOT 1 (-325 5075);
DOT 1 (-325 5125);
DOT 1 (-325 5225);
DOT 1 (-325 5175);
DOT 1 (-325 5325);
DOT 1 (-325 5375);
DOT 1 (-325 5275);
DOT 1 (-325 5475);
DOT 1 (-325 5425);
DOT 1 (-325 5575);
DOT 1 (-325 5625);
DOT 1 (-325 5525);
DOT 1 (-325 5725);
DOT 1 (-325 5675);
DOT 1 (-325 5825);
DOT 1 (-325 5875);
DOT 1 (-325 5775);
DOT 1 (-325 5975);
DOT 1 (-325 5925);
DOT 1 (-325 6025);
DOT 1 (-325 6125);
DOT 1 (-325 6075);
DOT 1 (-1650 6225);
DOT 1 (-1650 6175);
DOT 1 (-1650 6275);
DOT 1 (-1650 6325);
DOT 1 (-1650 6375);
DOT 1 (-325 6225);
DOT 1 (-325 6175);
DOT 1 (-325 6275);
DOT 1 (-325 6375);
DOT 1 (-325 6325);
DOT 1 (-1650 575);
DOT 1 (-1650 525);
QUIT
